FILE_TYPE = MACRO_DRAWING;
SET COLOR_WIRE YELLOW;
SET COLOR_PROP ORANGE;
SET COLOR_DOT WHITE;
SET COLOR_ARC YELLOW;
SET COLOR_BODY GREEN;
SET COLOR_NOTE PURPLE;
SET PROP_DISPLAY VALUE;
SET PAGE_NUMBER P17;
FORCEADD GENOA_SP5..8
(-4600 3600);
FORCEPROP 1 LAST LOCATION U25
J 0
(-5245 6431);
DISPLAY 0.489362 (-5245 6431);
PAINT SKYBLUE (-5245 6431);
FORCEPROP 0 LAST $SEC 8
J 0
(-5225 6475);
DISPLAY 0.680851 (-5225 6475);
PAINT MONO (-5225 6475);
DISPLAY INVISIBLE (-5225 6475);
FORCEPROP 0 LAST CDS_SEC 8
J 0
(-5250 6400);
DISPLAY 1.021277 (-5250 6400);
DISPLAY INVISIBLE (-5250 6400);
FORCEPROP 0 LASTPIN (-5400 2975) $PN BC12
J 2
(-5410 2985);
DISPLAY 0.489362 (-5410 2985);
PAINT MONO (-5410 2985);
FORCEPROP 0 LASTPIN (-5400 2925) $PN BD13
J 2
(-5410 2935);
DISPLAY 0.489362 (-5410 2935);
PAINT MONO (-5410 2935);
FORCEPROP 0 LASTPIN (-5400 1825) $PN BF13
J 2
(-5410 1835);
DISPLAY 0.489362 (-5410 1835);
PAINT MONO (-5410 1835);
FORCEPROP 0 LASTPIN (-5400 1775) $PN BG12
J 2
(-5410 1785);
DISPLAY 0.489362 (-5410 1785);
PAINT MONO (-5410 1785);
FORCEPROP 0 LASTPIN (-5400 2125) $PN AT14
J 2
(-5410 2135);
DISPLAY 0.489362 (-5410 2135);
PAINT MONO (-5410 2135);
FORCEPROP 0 LASTPIN (-5400 2025) $PN AU14
J 2
(-5410 2035);
DISPLAY 0.489362 (-5410 2035);
PAINT MONO (-5410 2035);
FORCEPROP 0 LASTPIN (-5400 2825) $PN AU12
J 2
(-5410 2835);
DISPLAY 0.489362 (-5410 2835);
PAINT MONO (-5410 2835);
FORCEPROP 0 LASTPIN (-5400 2775) $PN AV14
J 2
(-5410 2785);
DISPLAY 0.489362 (-5410 2785);
PAINT MONO (-5410 2785);
FORCEPROP 0 LASTPIN (-5400 2675) $PN BN14
J 2
(-5410 2685);
DISPLAY 0.489362 (-5410 2685);
PAINT MONO (-5410 2685);
FORCEPROP 0 LASTPIN (-5400 1675) $PN AV13
J 2
(-5410 1685);
DISPLAY 0.489362 (-5410 1685);
PAINT MONO (-5410 1685);
FORCEPROP 0 LASTPIN (-5400 1625) $PN AW14
J 2
(-5410 1635);
DISPLAY 0.489362 (-5410 1635);
PAINT MONO (-5410 1635);
FORCEPROP 0 LASTPIN (-5400 1525) $PN BP14
J 2
(-5410 1535);
DISPLAY 0.489362 (-5410 1535);
PAINT MONO (-5410 1535);
FORCEPROP 0 LASTPIN (-5400 3825) $PN AW12
J 2
(-5410 3835);
DISPLAY 0.489362 (-5410 3835);
PAINT MONO (-5410 3835);
FORCEPROP 0 LASTPIN (-5400 3775) $PN AY13
J 2
(-5410 3785);
DISPLAY 0.489362 (-5410 3785);
PAINT MONO (-5410 3785);
FORCEPROP 0 LASTPIN (-5400 3725) $PN AY14
J 2
(-5410 3735);
DISPLAY 0.489362 (-5410 3735);
PAINT MONO (-5410 3735);
FORCEPROP 0 LASTPIN (-5400 3675) $PN BA14
J 2
(-5410 3685);
DISPLAY 0.489362 (-5410 3685);
PAINT MONO (-5410 3685);
FORCEPROP 0 LASTPIN (-5400 3625) $PN BA12
J 2
(-5410 3635);
DISPLAY 0.489362 (-5410 3635);
PAINT MONO (-5410 3635);
FORCEPROP 0 LASTPIN (-5400 3575) $PN BB13
J 2
(-5410 3585);
DISPLAY 0.489362 (-5410 3585);
PAINT MONO (-5410 3585);
FORCEPROP 0 LASTPIN (-5400 3525) $PN BB14
J 2
(-5410 3535);
DISPLAY 0.489362 (-5410 3535);
PAINT MONO (-5410 3535);
FORCEPROP 0 LASTPIN (-3800 2375) $PN AJ12
J 0
(-3790 2385);
DISPLAY 0.489362 (-3790 2385);
PAINT MONO (-3790 2385);
FORCEPROP 0 LASTPIN (-3800 2325) $PN AK14
J 0
(-3790 2335);
DISPLAY 0.489362 (-3790 2335);
PAINT MONO (-3790 2335);
FORCEPROP 0 LASTPIN (-3800 2275) $PN AK13
J 0
(-3790 2285);
DISPLAY 0.489362 (-3790 2285);
PAINT MONO (-3790 2285);
FORCEPROP 0 LASTPIN (-3800 2225) $PN AL14
J 0
(-3790 2235);
DISPLAY 0.489362 (-3790 2235);
PAINT MONO (-3790 2235);
FORCEPROP 0 LASTPIN (-3800 2175) $PN AN12
J 0
(-3790 2185);
DISPLAY 0.489362 (-3790 2185);
PAINT MONO (-3790 2185);
FORCEPROP 0 LASTPIN (-3800 2125) $PN AP14
J 0
(-3790 2135);
DISPLAY 0.489362 (-3790 2135);
PAINT MONO (-3790 2135);
FORCEPROP 0 LASTPIN (-3800 2075) $PN AP13
J 0
(-3790 2085);
DISPLAY 0.489362 (-3790 2085);
PAINT MONO (-3790 2085);
FORCEPROP 0 LASTPIN (-3800 2025) $PN AR14
J 0
(-3790 2035);
DISPLAY 0.489362 (-3790 2035);
PAINT MONO (-3790 2035);
FORCEPROP 0 LASTPIN (-3800 5975) $PN E12
J 0
(-3790 5985);
DISPLAY 0.489362 (-3790 5985);
PAINT MONO (-3790 5985);
FORCEPROP 0 LASTPIN (-3800 5925) $PN F14
J 0
(-3790 5935);
DISPLAY 0.489362 (-3790 5935);
PAINT MONO (-3790 5935);
FORCEPROP 0 LASTPIN (-3800 5875) $PN F13
J 0
(-3790 5885);
DISPLAY 0.489362 (-3790 5885);
PAINT MONO (-3790 5885);
FORCEPROP 0 LASTPIN (-3800 5825) $PN G14
J 0
(-3790 5835);
DISPLAY 0.489362 (-3790 5835);
PAINT MONO (-3790 5835);
FORCEPROP 0 LASTPIN (-3800 5775) $PN J12
J 0
(-3790 5785);
DISPLAY 0.489362 (-3790 5785);
PAINT MONO (-3790 5785);
FORCEPROP 0 LASTPIN (-3800 5725) $PN K14
J 0
(-3790 5735);
DISPLAY 0.489362 (-3790 5735);
PAINT MONO (-3790 5735);
FORCEPROP 0 LASTPIN (-3800 5675) $PN K13
J 0
(-3790 5685);
DISPLAY 0.489362 (-3790 5685);
PAINT MONO (-3790 5685);
FORCEPROP 0 LASTPIN (-3800 5625) $PN L14
J 0
(-3790 5635);
DISPLAY 0.489362 (-3790 5635);
PAINT MONO (-3790 5635);
FORCEPROP 0 LASTPIN (-3800 5525) $PN L12
J 0
(-3790 5535);
DISPLAY 0.489362 (-3790 5535);
PAINT MONO (-3790 5535);
FORCEPROP 0 LASTPIN (-3800 5475) $PN M14
J 0
(-3790 5485);
DISPLAY 0.489362 (-3790 5485);
PAINT MONO (-3790 5485);
FORCEPROP 0 LASTPIN (-3800 5425) $PN M13
J 0
(-3790 5435);
DISPLAY 0.489362 (-3790 5435);
PAINT MONO (-3790 5435);
FORCEPROP 0 LASTPIN (-3800 5375) $PN N14
J 0
(-3790 5385);
DISPLAY 0.489362 (-3790 5385);
PAINT MONO (-3790 5385);
FORCEPROP 0 LASTPIN (-3800 5325) $PN R12
J 0
(-3790 5335);
DISPLAY 0.489362 (-3790 5335);
PAINT MONO (-3790 5335);
FORCEPROP 0 LASTPIN (-3800 5275) $PN T14
J 0
(-3790 5285);
DISPLAY 0.489362 (-3790 5285);
PAINT MONO (-3790 5285);
FORCEPROP 0 LASTPIN (-3800 5225) $PN T13
J 0
(-3790 5235);
DISPLAY 0.489362 (-3790 5235);
PAINT MONO (-3790 5235);
FORCEPROP 0 LASTPIN (-3800 5175) $PN U14
J 0
(-3790 5185);
DISPLAY 0.489362 (-3790 5185);
PAINT MONO (-3790 5185);
FORCEPROP 0 LASTPIN (-3800 5075) $PN U12
J 0
(-3790 5085);
DISPLAY 0.489362 (-3790 5085);
PAINT MONO (-3790 5085);
FORCEPROP 0 LASTPIN (-3800 5025) $PN V14
J 0
(-3790 5035);
DISPLAY 0.489362 (-3790 5035);
PAINT MONO (-3790 5035);
FORCEPROP 0 LASTPIN (-3800 4975) $PN V13
J 0
(-3790 4985);
DISPLAY 0.489362 (-3790 4985);
PAINT MONO (-3790 4985);
FORCEPROP 0 LASTPIN (-3800 4925) $PN W14
J 0
(-3790 4935);
DISPLAY 0.489362 (-3790 4935);
PAINT MONO (-3790 4935);
FORCEPROP 0 LASTPIN (-3800 4875) $PN AA12
J 0
(-3790 4885);
DISPLAY 0.489362 (-3790 4885);
PAINT MONO (-3790 4885);
FORCEPROP 0 LASTPIN (-3800 4825) $PN AB14
J 0
(-3790 4835);
DISPLAY 0.489362 (-3790 4835);
PAINT MONO (-3790 4835);
FORCEPROP 0 LASTPIN (-3800 4775) $PN AB13
J 0
(-3790 4785);
DISPLAY 0.489362 (-3790 4785);
PAINT MONO (-3790 4785);
FORCEPROP 0 LASTPIN (-3800 4725) $PN AC14
J 0
(-3790 4735);
DISPLAY 0.489362 (-3790 4735);
PAINT MONO (-3790 4735);
FORCEPROP 0 LASTPIN (-3800 4625) $PN AC12
J 0
(-3790 4635);
DISPLAY 0.489362 (-3790 4635);
PAINT MONO (-3790 4635);
FORCEPROP 0 LASTPIN (-3800 4575) $PN AD14
J 0
(-3790 4585);
DISPLAY 0.489362 (-3790 4585);
PAINT MONO (-3790 4585);
FORCEPROP 0 LASTPIN (-3800 4525) $PN AD13
J 0
(-3790 4535);
DISPLAY 0.489362 (-3790 4535);
PAINT MONO (-3790 4535);
FORCEPROP 0 LASTPIN (-3800 4475) $PN AE14
J 0
(-3790 4485);
DISPLAY 0.489362 (-3790 4485);
PAINT MONO (-3790 4485);
FORCEPROP 0 LASTPIN (-3800 4425) $PN AG12
J 0
(-3790 4435);
DISPLAY 0.489362 (-3790 4435);
PAINT MONO (-3790 4435);
FORCEPROP 0 LASTPIN (-3800 4375) $PN AH14
J 0
(-3790 4385);
DISPLAY 0.489362 (-3790 4385);
PAINT MONO (-3790 4385);
FORCEPROP 0 LASTPIN (-3800 4325) $PN AH13
J 0
(-3790 4335);
DISPLAY 0.489362 (-3790 4335);
PAINT MONO (-3790 4335);
FORCEPROP 0 LASTPIN (-3800 4275) $PN AJ14
J 0
(-3790 4285);
DISPLAY 0.489362 (-3790 4285);
PAINT MONO (-3790 4285);
FORCEPROP 0 LASTPIN (-5400 5975) $PN G12
J 2
(-5410 5985);
DISPLAY 0.489362 (-5410 5985);
PAINT MONO (-5410 5985);
FORCEPROP 0 LASTPIN (-5400 5875) $PN N12
J 2
(-5410 5885);
DISPLAY 0.489362 (-5410 5885);
PAINT MONO (-5410 5885);
FORCEPROP 0 LASTPIN (-5400 5775) $PN W12
J 2
(-5410 5785);
DISPLAY 0.489362 (-5410 5785);
PAINT MONO (-5410 5785);
FORCEPROP 0 LASTPIN (-5400 5675) $PN AE12
J 2
(-5410 5685);
DISPLAY 0.489362 (-5410 5685);
PAINT MONO (-5410 5685);
FORCEPROP 0 LASTPIN (-5400 5575) $PN AL12
J 2
(-5410 5585);
DISPLAY 0.489362 (-5410 5585);
PAINT MONO (-5410 5585);
FORCEPROP 0 LASTPIN (-5400 5475) $PN J14
J 2
(-5410 5485);
DISPLAY 0.489362 (-5410 5485);
PAINT MONO (-5410 5485);
FORCEPROP 0 LASTPIN (-5400 5375) $PN R14
J 2
(-5410 5385);
DISPLAY 0.489362 (-5410 5385);
PAINT MONO (-5410 5385);
FORCEPROP 0 LASTPIN (-5400 5275) $PN AA14
J 2
(-5410 5285);
DISPLAY 0.489362 (-5410 5285);
PAINT MONO (-5410 5285);
FORCEPROP 0 LASTPIN (-5400 5175) $PN AG14
J 2
(-5410 5185);
DISPLAY 0.489362 (-5410 5185);
PAINT MONO (-5410 5185);
FORCEPROP 0 LASTPIN (-5400 5075) $PN AN14
J 2
(-5410 5085);
DISPLAY 0.489362 (-5410 5085);
PAINT MONO (-5410 5085);
FORCEPROP 0 LASTPIN (-5400 5925) $PN H13
J 2
(-5410 5935);
DISPLAY 0.489362 (-5410 5935);
PAINT MONO (-5410 5935);
FORCEPROP 0 LASTPIN (-5400 5825) $PN P13
J 2
(-5410 5835);
DISPLAY 0.489362 (-5410 5835);
PAINT MONO (-5410 5835);
FORCEPROP 0 LASTPIN (-5400 5725) $PN Y13
J 2
(-5410 5735);
DISPLAY 0.489362 (-5410 5735);
PAINT MONO (-5410 5735);
FORCEPROP 0 LASTPIN (-5400 5625) $PN AF13
J 2
(-5410 5635);
DISPLAY 0.489362 (-5410 5635);
PAINT MONO (-5410 5635);
FORCEPROP 0 LASTPIN (-5400 5525) $PN AM13
J 2
(-5410 5535);
DISPLAY 0.489362 (-5410 5535);
PAINT MONO (-5410 5535);
FORCEPROP 0 LASTPIN (-5400 5425) $PN H14
J 2
(-5410 5435);
DISPLAY 0.489362 (-5410 5435);
PAINT MONO (-5410 5435);
FORCEPROP 0 LASTPIN (-5400 5325) $PN P14
J 2
(-5410 5335);
DISPLAY 0.489362 (-5410 5335);
PAINT MONO (-5410 5335);
FORCEPROP 0 LASTPIN (-5400 5225) $PN Y14
J 2
(-5410 5235);
DISPLAY 0.489362 (-5410 5235);
PAINT MONO (-5410 5235);
FORCEPROP 0 LASTPIN (-5400 5125) $PN AF14
J 2
(-5410 5135);
DISPLAY 0.489362 (-5410 5135);
PAINT MONO (-5410 5135);
FORCEPROP 0 LASTPIN (-5400 5025) $PN AM14
J 2
(-5410 5035);
DISPLAY 0.489362 (-5410 5035);
PAINT MONO (-5410 5035);
FORCEPROP 0 LASTPIN (-5400 2575) $PN BC14
J 2
(-5410 2585);
DISPLAY 0.489362 (-5410 2585);
PAINT MONO (-5410 2585);
FORCEPROP 0 LASTPIN (-5400 2475) $PN BM14
J 2
(-5410 2485);
DISPLAY 0.489362 (-5410 2485);
PAINT MONO (-5410 2485);
FORCEPROP 0 LASTPIN (-5400 2425) $PN BN12
J 2
(-5410 2435);
DISPLAY 0.489362 (-5410 2435);
PAINT MONO (-5410 2435);
FORCEPROP 0 LASTPIN (-5400 2325) $PN BP13
J 2
(-5410 2335);
DISPLAY 0.489362 (-5410 2335);
PAINT MONO (-5410 2335);
FORCEPROP 0 LASTPIN (-5400 1425) $PN BL12
J 2
(-5410 1435);
DISPLAY 0.489362 (-5410 1435);
PAINT MONO (-5410 1435);
FORCEPROP 0 LASTPIN (-5400 1375) $PN BM13
J 2
(-5410 1385);
DISPLAY 0.489362 (-5410 1385);
PAINT MONO (-5410 1385);
FORCEPROP 0 LASTPIN (-5400 1275) $PN BR12
J 2
(-5410 1285);
DISPLAY 0.489362 (-5410 1285);
PAINT MONO (-5410 1285);
FORCEPROP 0 LASTPIN (-5400 3425) $PN BG14
J 2
(-5410 3435);
DISPLAY 0.489362 (-5410 3435);
PAINT MONO (-5410 3435);
FORCEPROP 0 LASTPIN (-5400 3375) $PN BH14
J 2
(-5410 3385);
DISPLAY 0.489362 (-5410 3385);
PAINT MONO (-5410 3385);
FORCEPROP 0 LASTPIN (-5400 3325) $PN BH13
J 2
(-5410 3335);
DISPLAY 0.489362 (-5410 3335);
PAINT MONO (-5410 3335);
FORCEPROP 0 LASTPIN (-5400 3275) $PN BJ12
J 2
(-5410 3285);
DISPLAY 0.489362 (-5410 3285);
PAINT MONO (-5410 3285);
FORCEPROP 0 LASTPIN (-5400 3225) $PN BJ14
J 2
(-5410 3235);
DISPLAY 0.489362 (-5410 3235);
PAINT MONO (-5410 3235);
FORCEPROP 0 LASTPIN (-5400 3175) $PN BK14
J 2
(-5410 3185);
DISPLAY 0.489362 (-5410 3185);
PAINT MONO (-5410 3185);
FORCEPROP 0 LASTPIN (-5400 3125) $PN BK13
J 2
(-5410 3135);
DISPLAY 0.489362 (-5410 3135);
PAINT MONO (-5410 3135);
FORCEPROP 0 LASTPIN (-3800 1925) $PN BY13
J 0
(-3790 1935);
DISPLAY 0.489362 (-3790 1935);
PAINT MONO (-3790 1935);
FORCEPROP 0 LASTPIN (-3800 1875) $PN CA14
J 0
(-3790 1885);
DISPLAY 0.489362 (-3790 1885);
PAINT MONO (-3790 1885);
FORCEPROP 0 LASTPIN (-3800 1825) $PN CA12
J 0
(-3790 1835);
DISPLAY 0.489362 (-3790 1835);
PAINT MONO (-3790 1835);
FORCEPROP 0 LASTPIN (-3800 1775) $PN CB14
J 0
(-3790 1785);
DISPLAY 0.489362 (-3790 1785);
PAINT MONO (-3790 1785);
FORCEPROP 0 LASTPIN (-3800 1725) $PN BT13
J 0
(-3790 1735);
DISPLAY 0.489362 (-3790 1735);
PAINT MONO (-3790 1735);
FORCEPROP 0 LASTPIN (-3800 1675) $PN BU14
J 0
(-3790 1685);
DISPLAY 0.489362 (-3790 1685);
PAINT MONO (-3790 1685);
FORCEPROP 0 LASTPIN (-3800 1625) $PN BU12
J 0
(-3790 1635);
DISPLAY 0.489362 (-3790 1635);
PAINT MONO (-3790 1635);
FORCEPROP 0 LASTPIN (-3800 1575) $PN BV14
J 0
(-3790 1585);
DISPLAY 0.489362 (-3790 1585);
PAINT MONO (-3790 1585);
FORCEPROP 0 LASTPIN (-3800 4175) $PN CB13
J 0
(-3790 4185);
DISPLAY 0.489362 (-3790 4185);
PAINT MONO (-3790 4185);
FORCEPROP 0 LASTPIN (-3800 4125) $PN CC14
J 0
(-3790 4135);
DISPLAY 0.489362 (-3790 4135);
PAINT MONO (-3790 4135);
FORCEPROP 0 LASTPIN (-3800 4075) $PN CC12
J 0
(-3790 4085);
DISPLAY 0.489362 (-3790 4085);
PAINT MONO (-3790 4085);
FORCEPROP 0 LASTPIN (-3800 4025) $PN CD14
J 0
(-3790 4035);
DISPLAY 0.489362 (-3790 4035);
PAINT MONO (-3790 4035);
FORCEPROP 0 LASTPIN (-3800 3975) $PN CF13
J 0
(-3790 3985);
DISPLAY 0.489362 (-3790 3985);
PAINT MONO (-3790 3985);
FORCEPROP 0 LASTPIN (-3800 3925) $PN CG14
J 0
(-3790 3935);
DISPLAY 0.489362 (-3790 3935);
PAINT MONO (-3790 3935);
FORCEPROP 0 LASTPIN (-3800 3875) $PN CG12
J 0
(-3790 3885);
DISPLAY 0.489362 (-3790 3885);
PAINT MONO (-3790 3885);
FORCEPROP 0 LASTPIN (-3800 3825) $PN CH14
J 0
(-3790 3835);
DISPLAY 0.489362 (-3790 3835);
PAINT MONO (-3790 3835);
FORCEPROP 0 LASTPIN (-3800 3725) $PN CH13
J 0
(-3790 3735);
DISPLAY 0.489362 (-3790 3735);
PAINT MONO (-3790 3735);
FORCEPROP 0 LASTPIN (-3800 3675) $PN CJ14
J 0
(-3790 3685);
DISPLAY 0.489362 (-3790 3685);
PAINT MONO (-3790 3685);
FORCEPROP 0 LASTPIN (-3800 3625) $PN CJ12
J 0
(-3790 3635);
DISPLAY 0.489362 (-3790 3635);
PAINT MONO (-3790 3635);
FORCEPROP 0 LASTPIN (-3800 3575) $PN CK14
J 0
(-3790 3585);
DISPLAY 0.489362 (-3790 3585);
PAINT MONO (-3790 3585);
FORCEPROP 0 LASTPIN (-3800 3525) $PN CM13
J 0
(-3790 3535);
DISPLAY 0.489362 (-3790 3535);
PAINT MONO (-3790 3535);
FORCEPROP 0 LASTPIN (-3800 3475) $PN CN14
J 0
(-3790 3485);
DISPLAY 0.489362 (-3790 3485);
PAINT MONO (-3790 3485);
FORCEPROP 0 LASTPIN (-3800 3425) $PN CN12
J 0
(-3790 3435);
DISPLAY 0.489362 (-3790 3435);
PAINT MONO (-3790 3435);
FORCEPROP 0 LASTPIN (-3800 3375) $PN CP14
J 0
(-3790 3385);
DISPLAY 0.489362 (-3790 3385);
PAINT MONO (-3790 3385);
FORCEPROP 0 LASTPIN (-3800 3275) $PN CP13
J 0
(-3790 3285);
DISPLAY 0.489362 (-3790 3285);
PAINT MONO (-3790 3285);
FORCEPROP 0 LASTPIN (-3800 3225) $PN CR14
J 0
(-3790 3235);
DISPLAY 0.489362 (-3790 3235);
PAINT MONO (-3790 3235);
FORCEPROP 0 LASTPIN (-3800 3175) $PN CR12
J 0
(-3790 3185);
DISPLAY 0.489362 (-3790 3185);
PAINT MONO (-3790 3185);
FORCEPROP 0 LASTPIN (-3800 3125) $PN CT14
J 0
(-3790 3135);
DISPLAY 0.489362 (-3790 3135);
PAINT MONO (-3790 3135);
FORCEPROP 0 LASTPIN (-3800 3075) $PN CV13
J 0
(-3790 3085);
DISPLAY 0.489362 (-3790 3085);
PAINT MONO (-3790 3085);
FORCEPROP 0 LASTPIN (-3800 3025) $PN CW14
J 0
(-3790 3035);
DISPLAY 0.489362 (-3790 3035);
PAINT MONO (-3790 3035);
FORCEPROP 0 LASTPIN (-3800 2975) $PN CW12
J 0
(-3790 2985);
DISPLAY 0.489362 (-3790 2985);
PAINT MONO (-3790 2985);
FORCEPROP 0 LASTPIN (-3800 2925) $PN CY14
J 0
(-3790 2935);
DISPLAY 0.489362 (-3790 2935);
PAINT MONO (-3790 2935);
FORCEPROP 0 LASTPIN (-3800 2825) $PN CY13
J 0
(-3790 2835);
DISPLAY 0.489362 (-3790 2835);
PAINT MONO (-3790 2835);
FORCEPROP 0 LASTPIN (-3800 2775) $PN DA14
J 0
(-3790 2785);
DISPLAY 0.489362 (-3790 2785);
PAINT MONO (-3790 2785);
FORCEPROP 0 LASTPIN (-3800 2725) $PN DA12
J 0
(-3790 2735);
DISPLAY 0.489362 (-3790 2735);
PAINT MONO (-3790 2735);
FORCEPROP 0 LASTPIN (-3800 2675) $PN DB14
J 0
(-3790 2685);
DISPLAY 0.489362 (-3790 2685);
PAINT MONO (-3790 2685);
FORCEPROP 0 LASTPIN (-3800 2625) $PN DD13
J 0
(-3790 2635);
DISPLAY 0.489362 (-3790 2635);
PAINT MONO (-3790 2635);
FORCEPROP 0 LASTPIN (-3800 2575) $PN DE14
J 0
(-3790 2585);
DISPLAY 0.489362 (-3790 2585);
PAINT MONO (-3790 2585);
FORCEPROP 0 LASTPIN (-3800 2525) $PN DE12
J 0
(-3790 2535);
DISPLAY 0.489362 (-3790 2535);
PAINT MONO (-3790 2535);
FORCEPROP 0 LASTPIN (-3800 2475) $PN DF14
J 0
(-3790 2485);
DISPLAY 0.489362 (-3790 2485);
PAINT MONO (-3790 2485);
FORCEPROP 0 LASTPIN (-5400 4925) $PN CD13
J 2
(-5410 4935);
DISPLAY 0.489362 (-5410 4935);
PAINT MONO (-5410 4935);
FORCEPROP 0 LASTPIN (-5400 4825) $PN CK13
J 2
(-5410 4835);
DISPLAY 0.489362 (-5410 4835);
PAINT MONO (-5410 4835);
FORCEPROP 0 LASTPIN (-5400 4725) $PN CT13
J 2
(-5410 4735);
DISPLAY 0.489362 (-5410 4735);
PAINT MONO (-5410 4735);
FORCEPROP 0 LASTPIN (-5400 4625) $PN DB13
J 2
(-5410 4635);
DISPLAY 0.489362 (-5410 4635);
PAINT MONO (-5410 4635);
FORCEPROP 0 LASTPIN (-5400 4525) $PN BY14
J 2
(-5410 4535);
DISPLAY 0.489362 (-5410 4535);
PAINT MONO (-5410 4535);
FORCEPROP 0 LASTPIN (-5400 4425) $PN CF14
J 2
(-5410 4435);
DISPLAY 0.489362 (-5410 4435);
PAINT MONO (-5410 4435);
FORCEPROP 0 LASTPIN (-5400 4325) $PN CM14
J 2
(-5410 4335);
DISPLAY 0.489362 (-5410 4335);
PAINT MONO (-5410 4335);
FORCEPROP 0 LASTPIN (-5400 4225) $PN CV14
J 2
(-5410 4235);
DISPLAY 0.489362 (-5410 4235);
PAINT MONO (-5410 4235);
FORCEPROP 0 LASTPIN (-5400 4125) $PN DD14
J 2
(-5410 4135);
DISPLAY 0.489362 (-5410 4135);
PAINT MONO (-5410 4135);
FORCEPROP 0 LASTPIN (-5400 4025) $PN BV13
J 2
(-5410 4035);
DISPLAY 0.489362 (-5410 4035);
PAINT MONO (-5410 4035);
FORCEPROP 0 LASTPIN (-5400 4875) $PN CE12
J 2
(-5410 4885);
DISPLAY 0.489362 (-5410 4885);
PAINT MONO (-5410 4885);
FORCEPROP 0 LASTPIN (-5400 4775) $PN CL12
J 2
(-5410 4785);
DISPLAY 0.489362 (-5410 4785);
PAINT MONO (-5410 4785);
FORCEPROP 0 LASTPIN (-5400 4675) $PN CU12
J 2
(-5410 4685);
DISPLAY 0.489362 (-5410 4685);
PAINT MONO (-5410 4685);
FORCEPROP 0 LASTPIN (-5400 4575) $PN DC12
J 2
(-5410 4585);
DISPLAY 0.489362 (-5410 4585);
PAINT MONO (-5410 4585);
FORCEPROP 0 LASTPIN (-5400 4475) $PN BW14
J 2
(-5410 4485);
DISPLAY 0.489362 (-5410 4485);
PAINT MONO (-5410 4485);
FORCEPROP 0 LASTPIN (-5400 4375) $PN CE14
J 2
(-5410 4385);
DISPLAY 0.489362 (-5410 4385);
PAINT MONO (-5410 4385);
FORCEPROP 0 LASTPIN (-5400 4275) $PN CL14
J 2
(-5410 4285);
DISPLAY 0.489362 (-5410 4285);
PAINT MONO (-5410 4285);
FORCEPROP 0 LASTPIN (-5400 4175) $PN CU14
J 2
(-5410 4185);
DISPLAY 0.489362 (-5410 4185);
PAINT MONO (-5410 4185);
FORCEPROP 0 LASTPIN (-5400 4075) $PN DC14
J 2
(-5410 4085);
DISPLAY 0.489362 (-5410 4085);
PAINT MONO (-5410 4085);
FORCEPROP 0 LASTPIN (-5400 3975) $PN BW12
J 2
(-5410 3985);
DISPLAY 0.489362 (-5410 3985);
PAINT MONO (-5410 3985);
FORCEPROP 0 LASTPIN (-5400 2225) $PN BL14
J 2
(-5410 2235);
DISPLAY 0.489362 (-5410 2235);
PAINT MONO (-5410 2235);
FORCEPROP 0 LASTPIN (-5400 1175) $PN BF14
J 2
(-5410 1185);
DISPLAY 0.489362 (-5410 1185);
PAINT MONO (-5410 1185);
FORCEPROP 2 LAST PART_TYPE SMLF
J 0
(-5250 6350);
DISPLAY 1.021277 (-5250 6350);
FORCEPROP 1 LAST MATERIAL IO
J 0
(-5245 6157);
DISPLAY 0.489362 (-5245 6157);
PAINT SKYBLUE (-5245 6157);
FORCEPROP 2 LAST VALUE SOCKET6096_13568-001
J 0
(-5250 6250);
DISPLAY 0.489362 (-5250 6250);
PAINT SKYBLUE (-5250 6250);
FORCEPROP 2 LAST CDS_LIB pure_quanta
J 0
(-4600 3600);
DISPLAY INVISIBLE (-4600 3600);
FORCEPROP 1 LAST CDS_LMAN_SYM_OUTLINE -650,2525,650,-2525
J 0
(-4600 3600);
DISPLAY 0.468085 (-4600 3600);
PAINT GREEN (-4600 3600);
DISPLAY INVISIBLE (-4600 3600);
FORCEPROP 1 LAST NEEDS_NO_SIZE TRUE
J 0
(-4600 3600);
DISPLAY 0.723404 (-4600 3600);
PAINT GREEN (-4600 3600);
DISPLAY INVISIBLE (-4600 3600);
FORCEPROP 1 LAST PATH I159
J 0
(-4600 3600);
DISPLAY 0.723404 (-4600 3600);
PAINT GREEN (-4600 3600);
DISPLAY INVISIBLE (-4600 3600);
FORCEPROP 1 LAST PART_NUMBER DGA^6000030
J 0
(-5245 6284);
DISPLAY 0.489362 (-5245 6284);
PAINT SKYBLUE (-5245 6284);
DISPLAY INVISIBLE (-5245 6284);
FORCEADD OFFPAGE..3
(-2600 6000);
FORCEPROP 2 LAST $XR0 93 
J 0
(-2386 6000);
DISPLAY 0.638298 (-2386 6000);
PAINT MONO (-2386 6000);
FORCEPROP 2 LAST CDS_LIB mstr_standard
J 0
(-2600 6000);
DISPLAY 0.723404 (-2600 6000);
PAINT MONO (-2600 6000);
DISPLAY INVISIBLE (-2600 6000);
FORCEPROP 1 LAST OFFPAGE TRUE
J 0
(-2275 5875);
DISPLAY 0.872340 (-2275 5875);
PAINT GREEN (-2275 5875);
DISPLAY INVISIBLE (-2275 5875);
FORCEPROP 1 LAST COMMENT_BODY TRUE
J 0
(-2650 5900);
DISPLAY 0.872340 (-2650 5900);
PAINT GREEN (-2650 5900);
DISPLAY INVISIBLE (-2650 5900);
FORCEPROP 2 LAST PATH I160
J 0
(-2375 6050);
DISPLAY 1.021277 (-2375 6050);
DISPLAY INVISIBLE (-2375 6050);
FORCEADD OFFPAGE..3
(-2600 4200);
FORCEPROP 2 LAST $XR0 93 
J 0
(-2386 4200);
DISPLAY 0.638298 (-2386 4200);
PAINT MONO (-2386 4200);
FORCEPROP 2 LAST CDS_LIB mstr_standard
J 0
(-2600 4200);
DISPLAY 0.723404 (-2600 4200);
PAINT MONO (-2600 4200);
DISPLAY INVISIBLE (-2600 4200);
FORCEPROP 1 LAST OFFPAGE TRUE
J 0
(-2275 4075);
DISPLAY 0.872340 (-2275 4075);
PAINT GREEN (-2275 4075);
DISPLAY INVISIBLE (-2275 4075);
FORCEPROP 1 LAST COMMENT_BODY TRUE
J 0
(-2650 4100);
DISPLAY 0.872340 (-2650 4100);
PAINT GREEN (-2650 4100);
DISPLAY INVISIBLE (-2650 4100);
FORCEPROP 2 LAST PATH I161
J 0
(-2375 4250);
DISPLAY 1.021277 (-2375 4250);
DISPLAY INVISIBLE (-2375 4250);
FORCEADD TAP..1
(-3325 5975);
FORCEPROP 3 LASTPIN (-3375 5975) SIG_NAME M_H_CPU0_SA_DQ<0>
J 0
(-3365 5985);
DISPLAY 0.659574 (-3365 5985);
PAINT MONO (-3365 5985);
DISPLAY INVISIBLE (-3365 5985);
FORCEPROP 1 LASTPIN (-3375 5975) BN 0
J 0
(-3387 5983);
DISPLAY 0.489362 (-3387 5983);
PAINT GREEN (-3387 5983);
FORCEPROP 2 LAST CDS_LIB mstr_standard
J 0
(-3325 5975);
DISPLAY 0.723404 (-3325 5975);
PAINT MONO (-3325 5975);
DISPLAY INVISIBLE (-3325 5975);
FORCEPROP 1 LAST BODY_TYPE PLUMBING
J 0
(-3325 6025);
DISPLAY 0.872340 (-3325 6025);
PAINT GREEN (-3325 6025);
DISPLAY INVISIBLE (-3325 6025);
FORCEPROP 1 LAST HDL_TAP TRUE
J 0
(-3000 5850);
DISPLAY 0.872340 (-3000 5850);
DISPLAY INVISIBLE (-3000 5850);
FORCEPROP 1 LAST PATH I162
J 0
(-3327 5975);
DISPLAY 0.872340 (-3327 5975);
PAINT GREEN (-3327 5975);
DISPLAY INVISIBLE (-3327 5975);
FORCEADD TAP..1
(-3325 5925);
FORCEPROP 3 LASTPIN (-3375 5925) SIG_NAME M_H_CPU0_SA_DQ<1>
J 0
(-3365 5935);
DISPLAY 0.659574 (-3365 5935);
PAINT MONO (-3365 5935);
DISPLAY INVISIBLE (-3365 5935);
FORCEPROP 1 LASTPIN (-3375 5925) BN 1
J 0
(-3387 5933);
DISPLAY 0.489362 (-3387 5933);
PAINT GREEN (-3387 5933);
FORCEPROP 2 LAST CDS_LIB mstr_standard
J 0
(-3325 5925);
DISPLAY 0.723404 (-3325 5925);
PAINT MONO (-3325 5925);
DISPLAY INVISIBLE (-3325 5925);
FORCEPROP 1 LAST BODY_TYPE PLUMBING
J 0
(-3325 5975);
DISPLAY 0.872340 (-3325 5975);
PAINT GREEN (-3325 5975);
DISPLAY INVISIBLE (-3325 5975);
FORCEPROP 1 LAST HDL_TAP TRUE
J 0
(-3000 5800);
DISPLAY 0.872340 (-3000 5800);
DISPLAY INVISIBLE (-3000 5800);
FORCEPROP 1 LAST PATH I163
J 0
(-3327 5925);
DISPLAY 0.872340 (-3327 5925);
PAINT GREEN (-3327 5925);
DISPLAY INVISIBLE (-3327 5925);
FORCEADD TAP..1
(-3325 5875);
FORCEPROP 3 LASTPIN (-3375 5875) SIG_NAME M_H_CPU0_SA_DQ<2>
J 0
(-3365 5885);
DISPLAY 0.659574 (-3365 5885);
PAINT MONO (-3365 5885);
DISPLAY INVISIBLE (-3365 5885);
FORCEPROP 1 LASTPIN (-3375 5875) BN 2
J 0
(-3387 5883);
DISPLAY 0.489362 (-3387 5883);
PAINT GREEN (-3387 5883);
FORCEPROP 2 LAST CDS_LIB mstr_standard
J 0
(-3325 5875);
DISPLAY 0.723404 (-3325 5875);
PAINT MONO (-3325 5875);
DISPLAY INVISIBLE (-3325 5875);
FORCEPROP 1 LAST BODY_TYPE PLUMBING
J 0
(-3325 5925);
DISPLAY 0.872340 (-3325 5925);
PAINT GREEN (-3325 5925);
DISPLAY INVISIBLE (-3325 5925);
FORCEPROP 1 LAST HDL_TAP TRUE
J 0
(-3000 5750);
DISPLAY 0.872340 (-3000 5750);
DISPLAY INVISIBLE (-3000 5750);
FORCEPROP 1 LAST PATH I164
J 0
(-3327 5875);
DISPLAY 0.872340 (-3327 5875);
PAINT GREEN (-3327 5875);
DISPLAY INVISIBLE (-3327 5875);
FORCEADD TAP..1
(-3325 5825);
FORCEPROP 3 LASTPIN (-3375 5825) SIG_NAME M_H_CPU0_SA_DQ<3>
J 0
(-3365 5835);
DISPLAY 0.659574 (-3365 5835);
PAINT MONO (-3365 5835);
DISPLAY INVISIBLE (-3365 5835);
FORCEPROP 1 LASTPIN (-3375 5825) BN 3
J 0
(-3387 5833);
DISPLAY 0.489362 (-3387 5833);
PAINT GREEN (-3387 5833);
FORCEPROP 2 LAST CDS_LIB mstr_standard
J 0
(-3325 5825);
DISPLAY 0.723404 (-3325 5825);
PAINT MONO (-3325 5825);
DISPLAY INVISIBLE (-3325 5825);
FORCEPROP 1 LAST BODY_TYPE PLUMBING
J 0
(-3325 5875);
DISPLAY 0.872340 (-3325 5875);
PAINT GREEN (-3325 5875);
DISPLAY INVISIBLE (-3325 5875);
FORCEPROP 1 LAST HDL_TAP TRUE
J 0
(-3000 5700);
DISPLAY 0.872340 (-3000 5700);
DISPLAY INVISIBLE (-3000 5700);
FORCEPROP 1 LAST PATH I165
J 0
(-3327 5825);
DISPLAY 0.872340 (-3327 5825);
PAINT GREEN (-3327 5825);
DISPLAY INVISIBLE (-3327 5825);
FORCEADD TAP..1
(-3325 5775);
FORCEPROP 3 LASTPIN (-3375 5775) SIG_NAME M_H_CPU0_SA_DQ<4>
J 0
(-3365 5785);
DISPLAY 0.659574 (-3365 5785);
PAINT MONO (-3365 5785);
DISPLAY INVISIBLE (-3365 5785);
FORCEPROP 1 LASTPIN (-3375 5775) BN 4
J 0
(-3387 5783);
DISPLAY 0.489362 (-3387 5783);
PAINT GREEN (-3387 5783);
FORCEPROP 2 LAST CDS_LIB mstr_standard
J 0
(-3325 5775);
DISPLAY 0.723404 (-3325 5775);
PAINT MONO (-3325 5775);
DISPLAY INVISIBLE (-3325 5775);
FORCEPROP 1 LAST BODY_TYPE PLUMBING
J 0
(-3325 5825);
DISPLAY 0.872340 (-3325 5825);
PAINT GREEN (-3325 5825);
DISPLAY INVISIBLE (-3325 5825);
FORCEPROP 1 LAST HDL_TAP TRUE
J 0
(-3000 5650);
DISPLAY 0.872340 (-3000 5650);
DISPLAY INVISIBLE (-3000 5650);
FORCEPROP 1 LAST PATH I166
J 0
(-3327 5775);
DISPLAY 0.872340 (-3327 5775);
PAINT GREEN (-3327 5775);
DISPLAY INVISIBLE (-3327 5775);
FORCEADD TAP..1
(-3325 5675);
FORCEPROP 3 LASTPIN (-3375 5675) SIG_NAME M_H_CPU0_SA_DQ<6>
J 0
(-3365 5685);
DISPLAY 0.659574 (-3365 5685);
PAINT MONO (-3365 5685);
DISPLAY INVISIBLE (-3365 5685);
FORCEPROP 1 LASTPIN (-3375 5675) BN 6
J 0
(-3387 5683);
DISPLAY 0.489362 (-3387 5683);
PAINT GREEN (-3387 5683);
FORCEPROP 2 LAST CDS_LIB mstr_standard
J 0
(-3325 5675);
DISPLAY 0.723404 (-3325 5675);
PAINT MONO (-3325 5675);
DISPLAY INVISIBLE (-3325 5675);
FORCEPROP 1 LAST BODY_TYPE PLUMBING
J 0
(-3325 5725);
DISPLAY 0.872340 (-3325 5725);
PAINT GREEN (-3325 5725);
DISPLAY INVISIBLE (-3325 5725);
FORCEPROP 1 LAST HDL_TAP TRUE
J 0
(-3000 5550);
DISPLAY 0.872340 (-3000 5550);
DISPLAY INVISIBLE (-3000 5550);
FORCEPROP 1 LAST PATH I167
J 0
(-3327 5675);
DISPLAY 0.872340 (-3327 5675);
PAINT GREEN (-3327 5675);
DISPLAY INVISIBLE (-3327 5675);
FORCEADD TAP..1
(-3325 5725);
FORCEPROP 3 LASTPIN (-3375 5725) SIG_NAME M_H_CPU0_SA_DQ<5>
J 0
(-3365 5735);
DISPLAY 0.659574 (-3365 5735);
PAINT MONO (-3365 5735);
DISPLAY INVISIBLE (-3365 5735);
FORCEPROP 1 LASTPIN (-3375 5725) BN 5
J 0
(-3387 5733);
DISPLAY 0.489362 (-3387 5733);
PAINT GREEN (-3387 5733);
FORCEPROP 2 LAST CDS_LIB mstr_standard
J 0
(-3325 5725);
DISPLAY 0.723404 (-3325 5725);
PAINT MONO (-3325 5725);
DISPLAY INVISIBLE (-3325 5725);
FORCEPROP 1 LAST BODY_TYPE PLUMBING
J 0
(-3325 5775);
DISPLAY 0.872340 (-3325 5775);
PAINT GREEN (-3325 5775);
DISPLAY INVISIBLE (-3325 5775);
FORCEPROP 1 LAST HDL_TAP TRUE
J 0
(-3000 5600);
DISPLAY 0.872340 (-3000 5600);
DISPLAY INVISIBLE (-3000 5600);
FORCEPROP 1 LAST PATH I168
J 0
(-3327 5725);
DISPLAY 0.872340 (-3327 5725);
PAINT GREEN (-3327 5725);
DISPLAY INVISIBLE (-3327 5725);
FORCEADD TAP..1
(-3325 5425);
FORCEPROP 3 LASTPIN (-3375 5425) SIG_NAME M_H_CPU0_SA_DQ<10>
J 0
(-3365 5435);
DISPLAY 0.659574 (-3365 5435);
PAINT MONO (-3365 5435);
DISPLAY INVISIBLE (-3365 5435);
FORCEPROP 1 LASTPIN (-3375 5425) BN 10
J 0
(-3387 5433);
DISPLAY 0.489362 (-3387 5433);
PAINT GREEN (-3387 5433);
FORCEPROP 2 LAST CDS_LIB mstr_standard
J 0
(-3325 5425);
DISPLAY 0.723404 (-3325 5425);
PAINT MONO (-3325 5425);
DISPLAY INVISIBLE (-3325 5425);
FORCEPROP 1 LAST BODY_TYPE PLUMBING
J 0
(-3325 5475);
DISPLAY 0.872340 (-3325 5475);
PAINT GREEN (-3325 5475);
DISPLAY INVISIBLE (-3325 5475);
FORCEPROP 1 LAST HDL_TAP TRUE
J 0
(-3000 5300);
DISPLAY 0.872340 (-3000 5300);
DISPLAY INVISIBLE (-3000 5300);
FORCEPROP 1 LAST PATH I169
J 0
(-3327 5425);
DISPLAY 0.872340 (-3327 5425);
PAINT GREEN (-3327 5425);
DISPLAY INVISIBLE (-3327 5425);
FORCEADD TAP..1
(-3325 5525);
FORCEPROP 3 LASTPIN (-3375 5525) SIG_NAME M_H_CPU0_SA_DQ<8>
J 0
(-3365 5535);
DISPLAY 0.659574 (-3365 5535);
PAINT MONO (-3365 5535);
DISPLAY INVISIBLE (-3365 5535);
FORCEPROP 1 LASTPIN (-3375 5525) BN 8
J 0
(-3387 5533);
DISPLAY 0.489362 (-3387 5533);
PAINT GREEN (-3387 5533);
FORCEPROP 2 LAST CDS_LIB mstr_standard
J 0
(-3325 5525);
DISPLAY 0.723404 (-3325 5525);
PAINT MONO (-3325 5525);
DISPLAY INVISIBLE (-3325 5525);
FORCEPROP 1 LAST BODY_TYPE PLUMBING
J 0
(-3325 5575);
DISPLAY 0.872340 (-3325 5575);
PAINT GREEN (-3325 5575);
DISPLAY INVISIBLE (-3325 5575);
FORCEPROP 1 LAST HDL_TAP TRUE
J 0
(-3000 5400);
DISPLAY 0.872340 (-3000 5400);
DISPLAY INVISIBLE (-3000 5400);
FORCEPROP 1 LAST PATH I170
J 0
(-3327 5525);
DISPLAY 0.872340 (-3327 5525);
PAINT GREEN (-3327 5525);
DISPLAY INVISIBLE (-3327 5525);
FORCEADD TAP..1
(-3325 5625);
FORCEPROP 3 LASTPIN (-3375 5625) SIG_NAME M_H_CPU0_SA_DQ<7>
J 0
(-3365 5635);
DISPLAY 0.659574 (-3365 5635);
PAINT MONO (-3365 5635);
DISPLAY INVISIBLE (-3365 5635);
FORCEPROP 1 LASTPIN (-3375 5625) BN 7
J 0
(-3387 5633);
DISPLAY 0.489362 (-3387 5633);
PAINT GREEN (-3387 5633);
FORCEPROP 2 LAST CDS_LIB mstr_standard
J 0
(-3325 5625);
DISPLAY 0.723404 (-3325 5625);
PAINT MONO (-3325 5625);
DISPLAY INVISIBLE (-3325 5625);
FORCEPROP 1 LAST BODY_TYPE PLUMBING
J 0
(-3325 5675);
DISPLAY 0.872340 (-3325 5675);
PAINT GREEN (-3325 5675);
DISPLAY INVISIBLE (-3325 5675);
FORCEPROP 1 LAST HDL_TAP TRUE
J 0
(-3000 5500);
DISPLAY 0.872340 (-3000 5500);
DISPLAY INVISIBLE (-3000 5500);
FORCEPROP 1 LAST PATH I171
J 0
(-3327 5625);
DISPLAY 0.872340 (-3327 5625);
PAINT GREEN (-3327 5625);
DISPLAY INVISIBLE (-3327 5625);
FORCEADD TAP..1
(-3325 5475);
FORCEPROP 3 LASTPIN (-3375 5475) SIG_NAME M_H_CPU0_SA_DQ<9>
J 0
(-3365 5485);
DISPLAY 0.659574 (-3365 5485);
PAINT MONO (-3365 5485);
DISPLAY INVISIBLE (-3365 5485);
FORCEPROP 1 LASTPIN (-3375 5475) BN 9
J 0
(-3387 5483);
DISPLAY 0.489362 (-3387 5483);
PAINT GREEN (-3387 5483);
FORCEPROP 2 LAST CDS_LIB mstr_standard
J 0
(-3325 5475);
DISPLAY 0.723404 (-3325 5475);
PAINT MONO (-3325 5475);
DISPLAY INVISIBLE (-3325 5475);
FORCEPROP 1 LAST BODY_TYPE PLUMBING
J 0
(-3325 5525);
DISPLAY 0.872340 (-3325 5525);
PAINT GREEN (-3325 5525);
DISPLAY INVISIBLE (-3325 5525);
FORCEPROP 1 LAST HDL_TAP TRUE
J 0
(-3000 5350);
DISPLAY 0.872340 (-3000 5350);
DISPLAY INVISIBLE (-3000 5350);
FORCEPROP 1 LAST PATH I172
J 0
(-3327 5475);
DISPLAY 0.872340 (-3327 5475);
PAINT GREEN (-3327 5475);
DISPLAY INVISIBLE (-3327 5475);
FORCEADD TAP..1
(-3325 5225);
FORCEPROP 3 LASTPIN (-3375 5225) SIG_NAME M_H_CPU0_SA_DQ<14>
J 0
(-3365 5235);
DISPLAY 0.659574 (-3365 5235);
PAINT MONO (-3365 5235);
DISPLAY INVISIBLE (-3365 5235);
FORCEPROP 1 LASTPIN (-3375 5225) BN 14
J 0
(-3387 5233);
DISPLAY 0.489362 (-3387 5233);
PAINT GREEN (-3387 5233);
FORCEPROP 2 LAST CDS_LIB mstr_standard
J 0
(-3325 5225);
DISPLAY 0.723404 (-3325 5225);
PAINT MONO (-3325 5225);
DISPLAY INVISIBLE (-3325 5225);
FORCEPROP 1 LAST BODY_TYPE PLUMBING
J 0
(-3325 5275);
DISPLAY 0.872340 (-3325 5275);
PAINT GREEN (-3325 5275);
DISPLAY INVISIBLE (-3325 5275);
FORCEPROP 1 LAST HDL_TAP TRUE
J 0
(-3000 5100);
DISPLAY 0.872340 (-3000 5100);
DISPLAY INVISIBLE (-3000 5100);
FORCEPROP 1 LAST PATH I173
J 0
(-3327 5225);
DISPLAY 0.872340 (-3327 5225);
PAINT GREEN (-3327 5225);
DISPLAY INVISIBLE (-3327 5225);
FORCEADD TAP..1
(-3325 5175);
FORCEPROP 3 LASTPIN (-3375 5175) SIG_NAME M_H_CPU0_SA_DQ<15>
J 0
(-3365 5185);
DISPLAY 0.659574 (-3365 5185);
PAINT MONO (-3365 5185);
DISPLAY INVISIBLE (-3365 5185);
FORCEPROP 1 LASTPIN (-3375 5175) BN 15
J 0
(-3387 5183);
DISPLAY 0.489362 (-3387 5183);
PAINT GREEN (-3387 5183);
FORCEPROP 2 LAST CDS_LIB mstr_standard
J 0
(-3325 5175);
DISPLAY 0.723404 (-3325 5175);
PAINT MONO (-3325 5175);
DISPLAY INVISIBLE (-3325 5175);
FORCEPROP 1 LAST BODY_TYPE PLUMBING
J 0
(-3325 5225);
DISPLAY 0.872340 (-3325 5225);
PAINT GREEN (-3325 5225);
DISPLAY INVISIBLE (-3325 5225);
FORCEPROP 1 LAST HDL_TAP TRUE
J 0
(-3000 5050);
DISPLAY 0.872340 (-3000 5050);
DISPLAY INVISIBLE (-3000 5050);
FORCEPROP 1 LAST PATH I174
J 0
(-3327 5175);
DISPLAY 0.872340 (-3327 5175);
PAINT GREEN (-3327 5175);
DISPLAY INVISIBLE (-3327 5175);
FORCEADD TAP..1
(-3325 5275);
FORCEPROP 3 LASTPIN (-3375 5275) SIG_NAME M_H_CPU0_SA_DQ<13>
J 0
(-3365 5285);
DISPLAY 0.659574 (-3365 5285);
PAINT MONO (-3365 5285);
DISPLAY INVISIBLE (-3365 5285);
FORCEPROP 1 LASTPIN (-3375 5275) BN 13
J 0
(-3387 5283);
DISPLAY 0.489362 (-3387 5283);
PAINT GREEN (-3387 5283);
FORCEPROP 2 LAST CDS_LIB mstr_standard
J 0
(-3325 5275);
DISPLAY 0.723404 (-3325 5275);
PAINT MONO (-3325 5275);
DISPLAY INVISIBLE (-3325 5275);
FORCEPROP 1 LAST BODY_TYPE PLUMBING
J 0
(-3325 5325);
DISPLAY 0.872340 (-3325 5325);
PAINT GREEN (-3325 5325);
DISPLAY INVISIBLE (-3325 5325);
FORCEPROP 1 LAST HDL_TAP TRUE
J 0
(-3000 5150);
DISPLAY 0.872340 (-3000 5150);
DISPLAY INVISIBLE (-3000 5150);
FORCEPROP 1 LAST PATH I175
J 0
(-3327 5275);
DISPLAY 0.872340 (-3327 5275);
PAINT GREEN (-3327 5275);
DISPLAY INVISIBLE (-3327 5275);
FORCEADD TAP..1
(-3325 5325);
FORCEPROP 3 LASTPIN (-3375 5325) SIG_NAME M_H_CPU0_SA_DQ<12>
J 0
(-3365 5335);
DISPLAY 0.659574 (-3365 5335);
PAINT MONO (-3365 5335);
DISPLAY INVISIBLE (-3365 5335);
FORCEPROP 1 LASTPIN (-3375 5325) BN 12
J 0
(-3387 5333);
DISPLAY 0.489362 (-3387 5333);
PAINT GREEN (-3387 5333);
FORCEPROP 2 LAST CDS_LIB mstr_standard
J 0
(-3325 5325);
DISPLAY 0.723404 (-3325 5325);
PAINT MONO (-3325 5325);
DISPLAY INVISIBLE (-3325 5325);
FORCEPROP 1 LAST BODY_TYPE PLUMBING
J 0
(-3325 5375);
DISPLAY 0.872340 (-3325 5375);
PAINT GREEN (-3325 5375);
DISPLAY INVISIBLE (-3325 5375);
FORCEPROP 1 LAST HDL_TAP TRUE
J 0
(-3000 5200);
DISPLAY 0.872340 (-3000 5200);
DISPLAY INVISIBLE (-3000 5200);
FORCEPROP 1 LAST PATH I176
J 0
(-3327 5325);
DISPLAY 0.872340 (-3327 5325);
PAINT GREEN (-3327 5325);
DISPLAY INVISIBLE (-3327 5325);
FORCEADD TAP..1
(-3325 5375);
FORCEPROP 3 LASTPIN (-3375 5375) SIG_NAME M_H_CPU0_SA_DQ<11>
J 0
(-3365 5385);
DISPLAY 0.659574 (-3365 5385);
PAINT MONO (-3365 5385);
DISPLAY INVISIBLE (-3365 5385);
FORCEPROP 1 LASTPIN (-3375 5375) BN 11
J 0
(-3387 5383);
DISPLAY 0.489362 (-3387 5383);
PAINT GREEN (-3387 5383);
FORCEPROP 2 LAST CDS_LIB mstr_standard
J 0
(-3325 5375);
DISPLAY 0.723404 (-3325 5375);
PAINT MONO (-3325 5375);
DISPLAY INVISIBLE (-3325 5375);
FORCEPROP 1 LAST BODY_TYPE PLUMBING
J 0
(-3325 5425);
DISPLAY 0.872340 (-3325 5425);
PAINT GREEN (-3325 5425);
DISPLAY INVISIBLE (-3325 5425);
FORCEPROP 1 LAST HDL_TAP TRUE
J 0
(-3000 5250);
DISPLAY 0.872340 (-3000 5250);
DISPLAY INVISIBLE (-3000 5250);
FORCEPROP 1 LAST PATH I177
J 0
(-3327 5375);
DISPLAY 0.872340 (-3327 5375);
PAINT GREEN (-3327 5375);
DISPLAY INVISIBLE (-3327 5375);
FORCEADD TAP..1
(-3325 4975);
FORCEPROP 3 LASTPIN (-3375 4975) SIG_NAME M_H_CPU0_SA_DQ<18>
J 0
(-3365 4985);
DISPLAY 0.659574 (-3365 4985);
PAINT MONO (-3365 4985);
DISPLAY INVISIBLE (-3365 4985);
FORCEPROP 1 LASTPIN (-3375 4975) BN 18
J 0
(-3387 4983);
DISPLAY 0.489362 (-3387 4983);
PAINT GREEN (-3387 4983);
FORCEPROP 2 LAST CDS_LIB mstr_standard
J 0
(-3325 4975);
DISPLAY 0.723404 (-3325 4975);
PAINT MONO (-3325 4975);
DISPLAY INVISIBLE (-3325 4975);
FORCEPROP 1 LAST BODY_TYPE PLUMBING
J 0
(-3325 5025);
DISPLAY 0.872340 (-3325 5025);
PAINT GREEN (-3325 5025);
DISPLAY INVISIBLE (-3325 5025);
FORCEPROP 1 LAST HDL_TAP TRUE
J 0
(-3000 4850);
DISPLAY 0.872340 (-3000 4850);
DISPLAY INVISIBLE (-3000 4850);
FORCEPROP 1 LAST PATH I178
J 0
(-3327 4975);
DISPLAY 0.872340 (-3327 4975);
PAINT GREEN (-3327 4975);
DISPLAY INVISIBLE (-3327 4975);
FORCEADD TAP..1
(-3325 4925);
FORCEPROP 3 LASTPIN (-3375 4925) SIG_NAME M_H_CPU0_SA_DQ<19>
J 0
(-3365 4935);
DISPLAY 0.659574 (-3365 4935);
PAINT MONO (-3365 4935);
DISPLAY INVISIBLE (-3365 4935);
FORCEPROP 1 LASTPIN (-3375 4925) BN 19
J 0
(-3387 4933);
DISPLAY 0.489362 (-3387 4933);
PAINT GREEN (-3387 4933);
FORCEPROP 2 LAST CDS_LIB mstr_standard
J 0
(-3325 4925);
DISPLAY 0.723404 (-3325 4925);
PAINT MONO (-3325 4925);
DISPLAY INVISIBLE (-3325 4925);
FORCEPROP 1 LAST BODY_TYPE PLUMBING
J 0
(-3325 4975);
DISPLAY 0.872340 (-3325 4975);
PAINT GREEN (-3325 4975);
DISPLAY INVISIBLE (-3325 4975);
FORCEPROP 1 LAST HDL_TAP TRUE
J 0
(-3000 4800);
DISPLAY 0.872340 (-3000 4800);
DISPLAY INVISIBLE (-3000 4800);
FORCEPROP 1 LAST PATH I179
J 0
(-3327 4925);
DISPLAY 0.872340 (-3327 4925);
PAINT GREEN (-3327 4925);
DISPLAY INVISIBLE (-3327 4925);
FORCEADD TAP..1
(-3325 4875);
FORCEPROP 3 LASTPIN (-3375 4875) SIG_NAME M_H_CPU0_SA_DQ<20>
J 0
(-3365 4885);
DISPLAY 0.659574 (-3365 4885);
PAINT MONO (-3365 4885);
DISPLAY INVISIBLE (-3365 4885);
FORCEPROP 1 LASTPIN (-3375 4875) BN 20
J 0
(-3387 4883);
DISPLAY 0.489362 (-3387 4883);
PAINT GREEN (-3387 4883);
FORCEPROP 2 LAST CDS_LIB mstr_standard
J 0
(-3325 4875);
DISPLAY 0.723404 (-3325 4875);
PAINT MONO (-3325 4875);
DISPLAY INVISIBLE (-3325 4875);
FORCEPROP 1 LAST BODY_TYPE PLUMBING
J 0
(-3325 4925);
DISPLAY 0.872340 (-3325 4925);
PAINT GREEN (-3325 4925);
DISPLAY INVISIBLE (-3325 4925);
FORCEPROP 1 LAST HDL_TAP TRUE
J 0
(-3000 4750);
DISPLAY 0.872340 (-3000 4750);
DISPLAY INVISIBLE (-3000 4750);
FORCEPROP 1 LAST PATH I180
J 0
(-3327 4875);
DISPLAY 0.872340 (-3327 4875);
PAINT GREEN (-3327 4875);
DISPLAY INVISIBLE (-3327 4875);
FORCEADD TAP..1
(-3325 5025);
FORCEPROP 3 LASTPIN (-3375 5025) SIG_NAME M_H_CPU0_SA_DQ<17>
J 0
(-3365 5035);
DISPLAY 0.659574 (-3365 5035);
PAINT MONO (-3365 5035);
DISPLAY INVISIBLE (-3365 5035);
FORCEPROP 1 LASTPIN (-3375 5025) BN 17
J 0
(-3387 5033);
DISPLAY 0.489362 (-3387 5033);
PAINT GREEN (-3387 5033);
FORCEPROP 2 LAST CDS_LIB mstr_standard
J 0
(-3325 5025);
DISPLAY 0.723404 (-3325 5025);
PAINT MONO (-3325 5025);
DISPLAY INVISIBLE (-3325 5025);
FORCEPROP 1 LAST BODY_TYPE PLUMBING
J 0
(-3325 5075);
DISPLAY 0.872340 (-3325 5075);
PAINT GREEN (-3325 5075);
DISPLAY INVISIBLE (-3325 5075);
FORCEPROP 1 LAST HDL_TAP TRUE
J 0
(-3000 4900);
DISPLAY 0.872340 (-3000 4900);
DISPLAY INVISIBLE (-3000 4900);
FORCEPROP 1 LAST PATH I181
J 0
(-3327 5025);
DISPLAY 0.872340 (-3327 5025);
PAINT GREEN (-3327 5025);
DISPLAY INVISIBLE (-3327 5025);
FORCEADD TAP..1
(-3325 5075);
FORCEPROP 3 LASTPIN (-3375 5075) SIG_NAME M_H_CPU0_SA_DQ<16>
J 0
(-3365 5085);
DISPLAY 0.659574 (-3365 5085);
PAINT MONO (-3365 5085);
DISPLAY INVISIBLE (-3365 5085);
FORCEPROP 1 LASTPIN (-3375 5075) BN 16
J 0
(-3387 5083);
DISPLAY 0.489362 (-3387 5083);
PAINT GREEN (-3387 5083);
FORCEPROP 2 LAST CDS_LIB mstr_standard
J 0
(-3325 5075);
DISPLAY 0.723404 (-3325 5075);
PAINT MONO (-3325 5075);
DISPLAY INVISIBLE (-3325 5075);
FORCEPROP 1 LAST BODY_TYPE PLUMBING
J 0
(-3325 5125);
DISPLAY 0.872340 (-3325 5125);
PAINT GREEN (-3325 5125);
DISPLAY INVISIBLE (-3325 5125);
FORCEPROP 1 LAST HDL_TAP TRUE
J 0
(-3000 4950);
DISPLAY 0.872340 (-3000 4950);
DISPLAY INVISIBLE (-3000 4950);
FORCEPROP 1 LAST PATH I182
J 0
(-3327 5075);
DISPLAY 0.872340 (-3327 5075);
PAINT GREEN (-3327 5075);
DISPLAY INVISIBLE (-3327 5075);
FORCEADD TAP..1
(-3325 4625);
FORCEPROP 3 LASTPIN (-3375 4625) SIG_NAME M_H_CPU0_SA_DQ<24>
J 0
(-3365 4635);
DISPLAY 0.659574 (-3365 4635);
PAINT MONO (-3365 4635);
DISPLAY INVISIBLE (-3365 4635);
FORCEPROP 1 LASTPIN (-3375 4625) BN 24
J 0
(-3387 4633);
DISPLAY 0.489362 (-3387 4633);
PAINT GREEN (-3387 4633);
FORCEPROP 2 LAST CDS_LIB mstr_standard
J 0
(-3325 4625);
DISPLAY 0.723404 (-3325 4625);
PAINT MONO (-3325 4625);
DISPLAY INVISIBLE (-3325 4625);
FORCEPROP 1 LAST BODY_TYPE PLUMBING
J 0
(-3325 4675);
DISPLAY 0.872340 (-3325 4675);
PAINT GREEN (-3325 4675);
DISPLAY INVISIBLE (-3325 4675);
FORCEPROP 1 LAST HDL_TAP TRUE
J 0
(-3000 4500);
DISPLAY 0.872340 (-3000 4500);
DISPLAY INVISIBLE (-3000 4500);
FORCEPROP 1 LAST PATH I183
J 0
(-3327 4625);
DISPLAY 0.872340 (-3327 4625);
PAINT GREEN (-3327 4625);
DISPLAY INVISIBLE (-3327 4625);
FORCEADD TAP..1
(-3325 4725);
FORCEPROP 3 LASTPIN (-3375 4725) SIG_NAME M_H_CPU0_SA_DQ<23>
J 0
(-3365 4735);
DISPLAY 0.659574 (-3365 4735);
PAINT MONO (-3365 4735);
DISPLAY INVISIBLE (-3365 4735);
FORCEPROP 1 LASTPIN (-3375 4725) BN 23
J 0
(-3387 4733);
DISPLAY 0.489362 (-3387 4733);
PAINT GREEN (-3387 4733);
FORCEPROP 2 LAST CDS_LIB mstr_standard
J 0
(-3325 4725);
DISPLAY 0.723404 (-3325 4725);
PAINT MONO (-3325 4725);
DISPLAY INVISIBLE (-3325 4725);
FORCEPROP 1 LAST BODY_TYPE PLUMBING
J 0
(-3325 4775);
DISPLAY 0.872340 (-3325 4775);
PAINT GREEN (-3325 4775);
DISPLAY INVISIBLE (-3325 4775);
FORCEPROP 1 LAST HDL_TAP TRUE
J 0
(-3000 4600);
DISPLAY 0.872340 (-3000 4600);
DISPLAY INVISIBLE (-3000 4600);
FORCEPROP 1 LAST PATH I184
J 0
(-3327 4725);
DISPLAY 0.872340 (-3327 4725);
PAINT GREEN (-3327 4725);
DISPLAY INVISIBLE (-3327 4725);
FORCEADD TAP..1
(-3325 4775);
FORCEPROP 3 LASTPIN (-3375 4775) SIG_NAME M_H_CPU0_SA_DQ<22>
J 0
(-3365 4785);
DISPLAY 0.659574 (-3365 4785);
PAINT MONO (-3365 4785);
DISPLAY INVISIBLE (-3365 4785);
FORCEPROP 1 LASTPIN (-3375 4775) BN 22
J 0
(-3387 4783);
DISPLAY 0.489362 (-3387 4783);
PAINT GREEN (-3387 4783);
FORCEPROP 2 LAST CDS_LIB mstr_standard
J 0
(-3325 4775);
DISPLAY 0.723404 (-3325 4775);
PAINT MONO (-3325 4775);
DISPLAY INVISIBLE (-3325 4775);
FORCEPROP 1 LAST BODY_TYPE PLUMBING
J 0
(-3325 4825);
DISPLAY 0.872340 (-3325 4825);
PAINT GREEN (-3325 4825);
DISPLAY INVISIBLE (-3325 4825);
FORCEPROP 1 LAST HDL_TAP TRUE
J 0
(-3000 4650);
DISPLAY 0.872340 (-3000 4650);
DISPLAY INVISIBLE (-3000 4650);
FORCEPROP 1 LAST PATH I185
J 0
(-3327 4775);
DISPLAY 0.872340 (-3327 4775);
PAINT GREEN (-3327 4775);
DISPLAY INVISIBLE (-3327 4775);
FORCEADD TAP..1
(-3325 4825);
FORCEPROP 3 LASTPIN (-3375 4825) SIG_NAME M_H_CPU0_SA_DQ<21>
J 0
(-3365 4835);
DISPLAY 0.659574 (-3365 4835);
PAINT MONO (-3365 4835);
DISPLAY INVISIBLE (-3365 4835);
FORCEPROP 1 LASTPIN (-3375 4825) BN 21
J 0
(-3387 4833);
DISPLAY 0.489362 (-3387 4833);
PAINT GREEN (-3387 4833);
FORCEPROP 2 LAST CDS_LIB mstr_standard
J 0
(-3325 4825);
DISPLAY 0.723404 (-3325 4825);
PAINT MONO (-3325 4825);
DISPLAY INVISIBLE (-3325 4825);
FORCEPROP 1 LAST BODY_TYPE PLUMBING
J 0
(-3325 4875);
DISPLAY 0.872340 (-3325 4875);
PAINT GREEN (-3325 4875);
DISPLAY INVISIBLE (-3325 4875);
FORCEPROP 1 LAST HDL_TAP TRUE
J 0
(-3000 4700);
DISPLAY 0.872340 (-3000 4700);
DISPLAY INVISIBLE (-3000 4700);
FORCEPROP 1 LAST PATH I186
J 0
(-3327 4825);
DISPLAY 0.872340 (-3327 4825);
PAINT GREEN (-3327 4825);
DISPLAY INVISIBLE (-3327 4825);
FORCEADD TAP..1
(-3325 4475);
FORCEPROP 3 LASTPIN (-3375 4475) SIG_NAME M_H_CPU0_SA_DQ<27>
J 0
(-3365 4485);
DISPLAY 0.659574 (-3365 4485);
PAINT MONO (-3365 4485);
DISPLAY INVISIBLE (-3365 4485);
FORCEPROP 1 LASTPIN (-3375 4475) BN 27
J 0
(-3387 4483);
DISPLAY 0.489362 (-3387 4483);
PAINT GREEN (-3387 4483);
FORCEPROP 2 LAST CDS_LIB mstr_standard
J 0
(-3325 4475);
DISPLAY 0.723404 (-3325 4475);
PAINT MONO (-3325 4475);
DISPLAY INVISIBLE (-3325 4475);
FORCEPROP 1 LAST BODY_TYPE PLUMBING
J 0
(-3325 4525);
DISPLAY 0.872340 (-3325 4525);
PAINT GREEN (-3325 4525);
DISPLAY INVISIBLE (-3325 4525);
FORCEPROP 1 LAST HDL_TAP TRUE
J 0
(-3000 4350);
DISPLAY 0.872340 (-3000 4350);
DISPLAY INVISIBLE (-3000 4350);
FORCEPROP 1 LAST PATH I187
J 0
(-3327 4475);
DISPLAY 0.872340 (-3327 4475);
PAINT GREEN (-3327 4475);
DISPLAY INVISIBLE (-3327 4475);
FORCEADD TAP..1
(-3325 4425);
FORCEPROP 3 LASTPIN (-3375 4425) SIG_NAME M_H_CPU0_SA_DQ<28>
J 0
(-3365 4435);
DISPLAY 0.659574 (-3365 4435);
PAINT MONO (-3365 4435);
DISPLAY INVISIBLE (-3365 4435);
FORCEPROP 1 LASTPIN (-3375 4425) BN 28
J 0
(-3387 4433);
DISPLAY 0.489362 (-3387 4433);
PAINT GREEN (-3387 4433);
FORCEPROP 2 LAST CDS_LIB mstr_standard
J 0
(-3325 4425);
DISPLAY 0.723404 (-3325 4425);
PAINT MONO (-3325 4425);
DISPLAY INVISIBLE (-3325 4425);
FORCEPROP 1 LAST BODY_TYPE PLUMBING
J 0
(-3325 4475);
DISPLAY 0.872340 (-3325 4475);
PAINT GREEN (-3325 4475);
DISPLAY INVISIBLE (-3325 4475);
FORCEPROP 1 LAST HDL_TAP TRUE
J 0
(-3000 4300);
DISPLAY 0.872340 (-3000 4300);
DISPLAY INVISIBLE (-3000 4300);
FORCEPROP 1 LAST PATH I188
J 0
(-3327 4425);
DISPLAY 0.872340 (-3327 4425);
PAINT GREEN (-3327 4425);
DISPLAY INVISIBLE (-3327 4425);
FORCEADD TAP..1
(-3325 4375);
FORCEPROP 3 LASTPIN (-3375 4375) SIG_NAME M_H_CPU0_SA_DQ<29>
J 0
(-3365 4385);
DISPLAY 0.659574 (-3365 4385);
PAINT MONO (-3365 4385);
DISPLAY INVISIBLE (-3365 4385);
FORCEPROP 1 LASTPIN (-3375 4375) BN 29
J 0
(-3387 4383);
DISPLAY 0.489362 (-3387 4383);
PAINT GREEN (-3387 4383);
FORCEPROP 2 LAST CDS_LIB mstr_standard
J 0
(-3325 4375);
DISPLAY 0.723404 (-3325 4375);
PAINT MONO (-3325 4375);
DISPLAY INVISIBLE (-3325 4375);
FORCEPROP 1 LAST BODY_TYPE PLUMBING
J 0
(-3325 4425);
DISPLAY 0.872340 (-3325 4425);
PAINT GREEN (-3325 4425);
DISPLAY INVISIBLE (-3325 4425);
FORCEPROP 1 LAST HDL_TAP TRUE
J 0
(-3000 4250);
DISPLAY 0.872340 (-3000 4250);
DISPLAY INVISIBLE (-3000 4250);
FORCEPROP 1 LAST PATH I189
J 0
(-3327 4375);
DISPLAY 0.872340 (-3327 4375);
PAINT GREEN (-3327 4375);
DISPLAY INVISIBLE (-3327 4375);
FORCEADD TAP..1
(-3325 4575);
FORCEPROP 3 LASTPIN (-3375 4575) SIG_NAME M_H_CPU0_SA_DQ<25>
J 0
(-3365 4585);
DISPLAY 0.659574 (-3365 4585);
PAINT MONO (-3365 4585);
DISPLAY INVISIBLE (-3365 4585);
FORCEPROP 1 LASTPIN (-3375 4575) BN 25
J 0
(-3387 4583);
DISPLAY 0.489362 (-3387 4583);
PAINT GREEN (-3387 4583);
FORCEPROP 2 LAST CDS_LIB mstr_standard
J 0
(-3325 4575);
DISPLAY 0.723404 (-3325 4575);
PAINT MONO (-3325 4575);
DISPLAY INVISIBLE (-3325 4575);
FORCEPROP 1 LAST BODY_TYPE PLUMBING
J 0
(-3325 4625);
DISPLAY 0.872340 (-3325 4625);
PAINT GREEN (-3325 4625);
DISPLAY INVISIBLE (-3325 4625);
FORCEPROP 1 LAST HDL_TAP TRUE
J 0
(-3000 4450);
DISPLAY 0.872340 (-3000 4450);
DISPLAY INVISIBLE (-3000 4450);
FORCEPROP 1 LAST PATH I190
J 0
(-3327 4575);
DISPLAY 0.872340 (-3327 4575);
PAINT GREEN (-3327 4575);
DISPLAY INVISIBLE (-3327 4575);
FORCEADD TAP..1
(-3325 4525);
FORCEPROP 3 LASTPIN (-3375 4525) SIG_NAME M_H_CPU0_SA_DQ<26>
J 0
(-3365 4535);
DISPLAY 0.659574 (-3365 4535);
PAINT MONO (-3365 4535);
DISPLAY INVISIBLE (-3365 4535);
FORCEPROP 1 LASTPIN (-3375 4525) BN 26
J 0
(-3387 4533);
DISPLAY 0.489362 (-3387 4533);
PAINT GREEN (-3387 4533);
FORCEPROP 2 LAST CDS_LIB mstr_standard
J 0
(-3325 4525);
DISPLAY 0.723404 (-3325 4525);
PAINT MONO (-3325 4525);
DISPLAY INVISIBLE (-3325 4525);
FORCEPROP 1 LAST BODY_TYPE PLUMBING
J 0
(-3325 4575);
DISPLAY 0.872340 (-3325 4575);
PAINT GREEN (-3325 4575);
DISPLAY INVISIBLE (-3325 4575);
FORCEPROP 1 LAST HDL_TAP TRUE
J 0
(-3000 4400);
DISPLAY 0.872340 (-3000 4400);
DISPLAY INVISIBLE (-3000 4400);
FORCEPROP 1 LAST PATH I191
J 0
(-3327 4525);
DISPLAY 0.872340 (-3327 4525);
PAINT GREEN (-3327 4525);
DISPLAY INVISIBLE (-3327 4525);
FORCEADD TAP..1
(-3325 4175);
FORCEPROP 3 LASTPIN (-3375 4175) SIG_NAME M_H_CPU0_SB_DQ<0>
J 0
(-3365 4185);
DISPLAY 0.659574 (-3365 4185);
PAINT MONO (-3365 4185);
DISPLAY INVISIBLE (-3365 4185);
FORCEPROP 1 LASTPIN (-3375 4175) BN 0
J 0
(-3387 4183);
DISPLAY 0.489362 (-3387 4183);
PAINT GREEN (-3387 4183);
FORCEPROP 2 LAST CDS_LIB mstr_standard
J 0
(-3325 4175);
DISPLAY 0.723404 (-3325 4175);
PAINT MONO (-3325 4175);
DISPLAY INVISIBLE (-3325 4175);
FORCEPROP 1 LAST BODY_TYPE PLUMBING
J 0
(-3325 4225);
DISPLAY 0.872340 (-3325 4225);
PAINT GREEN (-3325 4225);
DISPLAY INVISIBLE (-3325 4225);
FORCEPROP 1 LAST HDL_TAP TRUE
J 0
(-3000 4050);
DISPLAY 0.872340 (-3000 4050);
DISPLAY INVISIBLE (-3000 4050);
FORCEPROP 1 LAST PATH I192
J 0
(-3327 4175);
DISPLAY 0.872340 (-3327 4175);
PAINT GREEN (-3327 4175);
DISPLAY INVISIBLE (-3327 4175);
FORCEADD TAP..1
(-3325 4125);
FORCEPROP 3 LASTPIN (-3375 4125) SIG_NAME M_H_CPU0_SB_DQ<1>
J 0
(-3365 4135);
DISPLAY 0.659574 (-3365 4135);
PAINT MONO (-3365 4135);
DISPLAY INVISIBLE (-3365 4135);
FORCEPROP 1 LASTPIN (-3375 4125) BN 1
J 0
(-3387 4133);
DISPLAY 0.489362 (-3387 4133);
PAINT GREEN (-3387 4133);
FORCEPROP 2 LAST CDS_LIB mstr_standard
J 0
(-3325 4125);
DISPLAY 0.723404 (-3325 4125);
PAINT MONO (-3325 4125);
DISPLAY INVISIBLE (-3325 4125);
FORCEPROP 1 LAST BODY_TYPE PLUMBING
J 0
(-3325 4175);
DISPLAY 0.872340 (-3325 4175);
PAINT GREEN (-3325 4175);
DISPLAY INVISIBLE (-3325 4175);
FORCEPROP 1 LAST HDL_TAP TRUE
J 0
(-3000 4000);
DISPLAY 0.872340 (-3000 4000);
DISPLAY INVISIBLE (-3000 4000);
FORCEPROP 1 LAST PATH I193
J 0
(-3327 4125);
DISPLAY 0.872340 (-3327 4125);
PAINT GREEN (-3327 4125);
DISPLAY INVISIBLE (-3327 4125);
FORCEADD TAP..1
(-3325 4275);
FORCEPROP 3 LASTPIN (-3375 4275) SIG_NAME M_H_CPU0_SA_DQ<31>
J 0
(-3365 4285);
DISPLAY 0.659574 (-3365 4285);
PAINT MONO (-3365 4285);
DISPLAY INVISIBLE (-3365 4285);
FORCEPROP 1 LASTPIN (-3375 4275) BN 31
J 0
(-3387 4283);
DISPLAY 0.489362 (-3387 4283);
PAINT GREEN (-3387 4283);
FORCEPROP 2 LAST CDS_LIB mstr_standard
J 0
(-3325 4275);
DISPLAY 0.723404 (-3325 4275);
PAINT MONO (-3325 4275);
DISPLAY INVISIBLE (-3325 4275);
FORCEPROP 1 LAST BODY_TYPE PLUMBING
J 0
(-3325 4325);
DISPLAY 0.872340 (-3325 4325);
PAINT GREEN (-3325 4325);
DISPLAY INVISIBLE (-3325 4325);
FORCEPROP 1 LAST HDL_TAP TRUE
J 0
(-3000 4150);
DISPLAY 0.872340 (-3000 4150);
DISPLAY INVISIBLE (-3000 4150);
FORCEPROP 1 LAST PATH I194
J 0
(-3327 4275);
DISPLAY 0.872340 (-3327 4275);
PAINT GREEN (-3327 4275);
DISPLAY INVISIBLE (-3327 4275);
FORCEADD TAP..1
(-3325 4325);
FORCEPROP 3 LASTPIN (-3375 4325) SIG_NAME M_H_CPU0_SA_DQ<30>
J 0
(-3365 4335);
DISPLAY 0.659574 (-3365 4335);
PAINT MONO (-3365 4335);
DISPLAY INVISIBLE (-3365 4335);
FORCEPROP 1 LASTPIN (-3375 4325) BN 30
J 0
(-3387 4333);
DISPLAY 0.489362 (-3387 4333);
PAINT GREEN (-3387 4333);
FORCEPROP 2 LAST CDS_LIB mstr_standard
J 0
(-3325 4325);
DISPLAY 0.723404 (-3325 4325);
PAINT MONO (-3325 4325);
DISPLAY INVISIBLE (-3325 4325);
FORCEPROP 1 LAST BODY_TYPE PLUMBING
J 0
(-3325 4375);
DISPLAY 0.872340 (-3325 4375);
PAINT GREEN (-3325 4375);
DISPLAY INVISIBLE (-3325 4375);
FORCEPROP 1 LAST HDL_TAP TRUE
J 0
(-3000 4200);
DISPLAY 0.872340 (-3000 4200);
DISPLAY INVISIBLE (-3000 4200);
FORCEPROP 1 LAST PATH I195
J 0
(-3327 4325);
DISPLAY 0.872340 (-3327 4325);
PAINT GREEN (-3327 4325);
DISPLAY INVISIBLE (-3327 4325);
FORCEADD OFFPAGE..6
R 2
(-2725 2425);
FORCEPROP 2 LAST $XR0 93 
J 0
(-2511 2425);
DISPLAY 0.638298 (-2511 2425);
PAINT MONO (-2511 2425);
FORCEPROP 2 LAST CDS_LIB mstr_standard
J 2
(-2725 2425);
DISPLAY 0.723404 (-2725 2425);
PAINT MONO (-2725 2425);
DISPLAY INVISIBLE (-2725 2425);
FORCEPROP 1 LAST OFFPAGE TRUE
J 2
(-3050 2300);
DISPLAY 0.872340 (-3050 2300);
PAINT GREEN (-3050 2300);
DISPLAY INVISIBLE (-3050 2300);
FORCEPROP 1 LAST COMMENT_BODY TRUE
J 2
(-2825 2350);
DISPLAY 0.872340 (-2825 2350);
PAINT GREEN (-2825 2350);
DISPLAY INVISIBLE (-2825 2350);
FORCEPROP 2 LAST PATH I196
J 0
(-2500 2475);
DISPLAY 1.021277 (-2500 2475);
DISPLAY INVISIBLE (-2500 2475);
FORCEADD TAP..1
(-3325 4075);
FORCEPROP 3 LASTPIN (-3375 4075) SIG_NAME M_H_CPU0_SB_DQ<2>
J 0
(-3365 4085);
DISPLAY 0.659574 (-3365 4085);
PAINT MONO (-3365 4085);
DISPLAY INVISIBLE (-3365 4085);
FORCEPROP 1 LASTPIN (-3375 4075) BN 2
J 0
(-3387 4083);
DISPLAY 0.489362 (-3387 4083);
PAINT GREEN (-3387 4083);
FORCEPROP 2 LAST CDS_LIB mstr_standard
J 0
(-3325 4075);
DISPLAY 0.723404 (-3325 4075);
PAINT MONO (-3325 4075);
DISPLAY INVISIBLE (-3325 4075);
FORCEPROP 1 LAST BODY_TYPE PLUMBING
J 0
(-3325 4125);
DISPLAY 0.872340 (-3325 4125);
PAINT GREEN (-3325 4125);
DISPLAY INVISIBLE (-3325 4125);
FORCEPROP 1 LAST HDL_TAP TRUE
J 0
(-3000 3950);
DISPLAY 0.872340 (-3000 3950);
DISPLAY INVISIBLE (-3000 3950);
FORCEPROP 1 LAST PATH I197
J 0
(-3327 4075);
DISPLAY 0.872340 (-3327 4075);
PAINT GREEN (-3327 4075);
DISPLAY INVISIBLE (-3327 4075);
FORCEADD TAP..1
(-3325 4025);
FORCEPROP 3 LASTPIN (-3375 4025) SIG_NAME M_H_CPU0_SB_DQ<3>
J 0
(-3365 4035);
DISPLAY 0.659574 (-3365 4035);
PAINT MONO (-3365 4035);
DISPLAY INVISIBLE (-3365 4035);
FORCEPROP 1 LASTPIN (-3375 4025) BN 3
J 0
(-3387 4033);
DISPLAY 0.489362 (-3387 4033);
PAINT GREEN (-3387 4033);
FORCEPROP 2 LAST CDS_LIB mstr_standard
J 0
(-3325 4025);
DISPLAY 0.723404 (-3325 4025);
PAINT MONO (-3325 4025);
DISPLAY INVISIBLE (-3325 4025);
FORCEPROP 1 LAST BODY_TYPE PLUMBING
J 0
(-3325 4075);
DISPLAY 0.872340 (-3325 4075);
PAINT GREEN (-3325 4075);
DISPLAY INVISIBLE (-3325 4075);
FORCEPROP 1 LAST HDL_TAP TRUE
J 0
(-3000 3900);
DISPLAY 0.872340 (-3000 3900);
DISPLAY INVISIBLE (-3000 3900);
FORCEPROP 1 LAST PATH I198
J 0
(-3327 4025);
DISPLAY 0.872340 (-3327 4025);
PAINT GREEN (-3327 4025);
DISPLAY INVISIBLE (-3327 4025);
FORCEADD TAP..1
(-3325 3975);
FORCEPROP 3 LASTPIN (-3375 3975) SIG_NAME M_H_CPU0_SB_DQ<4>
J 0
(-3365 3985);
DISPLAY 0.659574 (-3365 3985);
PAINT MONO (-3365 3985);
DISPLAY INVISIBLE (-3365 3985);
FORCEPROP 1 LASTPIN (-3375 3975) BN 4
J 0
(-3387 3983);
DISPLAY 0.489362 (-3387 3983);
PAINT GREEN (-3387 3983);
FORCEPROP 2 LAST CDS_LIB mstr_standard
J 0
(-3325 3975);
DISPLAY 0.723404 (-3325 3975);
PAINT MONO (-3325 3975);
DISPLAY INVISIBLE (-3325 3975);
FORCEPROP 1 LAST BODY_TYPE PLUMBING
J 0
(-3325 4025);
DISPLAY 0.872340 (-3325 4025);
PAINT GREEN (-3325 4025);
DISPLAY INVISIBLE (-3325 4025);
FORCEPROP 1 LAST HDL_TAP TRUE
J 0
(-3000 3850);
DISPLAY 0.872340 (-3000 3850);
DISPLAY INVISIBLE (-3000 3850);
FORCEPROP 1 LAST PATH I199
J 0
(-3327 3975);
DISPLAY 0.872340 (-3327 3975);
PAINT GREEN (-3327 3975);
DISPLAY INVISIBLE (-3327 3975);
FORCEADD TAP..1
(-3325 3875);
FORCEPROP 3 LASTPIN (-3375 3875) SIG_NAME M_H_CPU0_SB_DQ<6>
J 0
(-3365 3885);
DISPLAY 0.659574 (-3365 3885);
PAINT MONO (-3365 3885);
DISPLAY INVISIBLE (-3365 3885);
FORCEPROP 1 LASTPIN (-3375 3875) BN 6
J 0
(-3387 3883);
DISPLAY 0.489362 (-3387 3883);
PAINT GREEN (-3387 3883);
FORCEPROP 2 LAST CDS_LIB mstr_standard
J 0
(-3325 3875);
DISPLAY 0.723404 (-3325 3875);
PAINT MONO (-3325 3875);
DISPLAY INVISIBLE (-3325 3875);
FORCEPROP 1 LAST BODY_TYPE PLUMBING
J 0
(-3325 3925);
DISPLAY 0.872340 (-3325 3925);
PAINT GREEN (-3325 3925);
DISPLAY INVISIBLE (-3325 3925);
FORCEPROP 1 LAST HDL_TAP TRUE
J 0
(-3000 3750);
DISPLAY 0.872340 (-3000 3750);
DISPLAY INVISIBLE (-3000 3750);
FORCEPROP 1 LAST PATH I200
J 0
(-3327 3875);
DISPLAY 0.872340 (-3327 3875);
PAINT GREEN (-3327 3875);
DISPLAY INVISIBLE (-3327 3875);
FORCEADD TAP..1
(-3325 3925);
FORCEPROP 3 LASTPIN (-3375 3925) SIG_NAME M_H_CPU0_SB_DQ<5>
J 0
(-3365 3935);
DISPLAY 0.659574 (-3365 3935);
PAINT MONO (-3365 3935);
DISPLAY INVISIBLE (-3365 3935);
FORCEPROP 1 LASTPIN (-3375 3925) BN 5
J 0
(-3387 3933);
DISPLAY 0.489362 (-3387 3933);
PAINT GREEN (-3387 3933);
FORCEPROP 2 LAST CDS_LIB mstr_standard
J 0
(-3325 3925);
DISPLAY 0.723404 (-3325 3925);
PAINT MONO (-3325 3925);
DISPLAY INVISIBLE (-3325 3925);
FORCEPROP 1 LAST BODY_TYPE PLUMBING
J 0
(-3325 3975);
DISPLAY 0.872340 (-3325 3975);
PAINT GREEN (-3325 3975);
DISPLAY INVISIBLE (-3325 3975);
FORCEPROP 1 LAST HDL_TAP TRUE
J 0
(-3000 3800);
DISPLAY 0.872340 (-3000 3800);
DISPLAY INVISIBLE (-3000 3800);
FORCEPROP 1 LAST PATH I201
J 0
(-3327 3925);
DISPLAY 0.872340 (-3327 3925);
PAINT GREEN (-3327 3925);
DISPLAY INVISIBLE (-3327 3925);
FORCEADD TAP..1
(-3325 3675);
FORCEPROP 3 LASTPIN (-3375 3675) SIG_NAME M_H_CPU0_SB_DQ<9>
J 0
(-3365 3685);
DISPLAY 0.659574 (-3365 3685);
PAINT MONO (-3365 3685);
DISPLAY INVISIBLE (-3365 3685);
FORCEPROP 1 LASTPIN (-3375 3675) BN 9
J 0
(-3387 3683);
DISPLAY 0.489362 (-3387 3683);
PAINT GREEN (-3387 3683);
FORCEPROP 2 LAST CDS_LIB mstr_standard
J 0
(-3325 3675);
DISPLAY 0.723404 (-3325 3675);
PAINT MONO (-3325 3675);
DISPLAY INVISIBLE (-3325 3675);
FORCEPROP 1 LAST BODY_TYPE PLUMBING
J 0
(-3325 3725);
DISPLAY 0.872340 (-3325 3725);
PAINT GREEN (-3325 3725);
DISPLAY INVISIBLE (-3325 3725);
FORCEPROP 1 LAST HDL_TAP TRUE
J 0
(-3000 3550);
DISPLAY 0.872340 (-3000 3550);
DISPLAY INVISIBLE (-3000 3550);
FORCEPROP 1 LAST PATH I202
J 0
(-3327 3675);
DISPLAY 0.872340 (-3327 3675);
PAINT GREEN (-3327 3675);
DISPLAY INVISIBLE (-3327 3675);
FORCEADD TAP..1
(-3325 3725);
FORCEPROP 3 LASTPIN (-3375 3725) SIG_NAME M_H_CPU0_SB_DQ<8>
J 0
(-3365 3735);
DISPLAY 0.659574 (-3365 3735);
PAINT MONO (-3365 3735);
DISPLAY INVISIBLE (-3365 3735);
FORCEPROP 1 LASTPIN (-3375 3725) BN 8
J 0
(-3387 3733);
DISPLAY 0.489362 (-3387 3733);
PAINT GREEN (-3387 3733);
FORCEPROP 2 LAST CDS_LIB mstr_standard
J 0
(-3325 3725);
DISPLAY 0.723404 (-3325 3725);
PAINT MONO (-3325 3725);
DISPLAY INVISIBLE (-3325 3725);
FORCEPROP 1 LAST BODY_TYPE PLUMBING
J 0
(-3325 3775);
DISPLAY 0.872340 (-3325 3775);
PAINT GREEN (-3325 3775);
DISPLAY INVISIBLE (-3325 3775);
FORCEPROP 1 LAST HDL_TAP TRUE
J 0
(-3000 3600);
DISPLAY 0.872340 (-3000 3600);
DISPLAY INVISIBLE (-3000 3600);
FORCEPROP 1 LAST PATH I203
J 0
(-3327 3725);
DISPLAY 0.872340 (-3327 3725);
PAINT GREEN (-3327 3725);
DISPLAY INVISIBLE (-3327 3725);
FORCEADD TAP..1
(-3325 3825);
FORCEPROP 3 LASTPIN (-3375 3825) SIG_NAME M_H_CPU0_SB_DQ<7>
J 0
(-3365 3835);
DISPLAY 0.659574 (-3365 3835);
PAINT MONO (-3365 3835);
DISPLAY INVISIBLE (-3365 3835);
FORCEPROP 1 LASTPIN (-3375 3825) BN 7
J 0
(-3387 3833);
DISPLAY 0.489362 (-3387 3833);
PAINT GREEN (-3387 3833);
FORCEPROP 2 LAST CDS_LIB mstr_standard
J 0
(-3325 3825);
DISPLAY 0.723404 (-3325 3825);
PAINT MONO (-3325 3825);
DISPLAY INVISIBLE (-3325 3825);
FORCEPROP 1 LAST BODY_TYPE PLUMBING
J 0
(-3325 3875);
DISPLAY 0.872340 (-3325 3875);
PAINT GREEN (-3325 3875);
DISPLAY INVISIBLE (-3325 3875);
FORCEPROP 1 LAST HDL_TAP TRUE
J 0
(-3000 3700);
DISPLAY 0.872340 (-3000 3700);
DISPLAY INVISIBLE (-3000 3700);
FORCEPROP 1 LAST PATH I204
J 0
(-3327 3825);
DISPLAY 0.872340 (-3327 3825);
PAINT GREEN (-3327 3825);
DISPLAY INVISIBLE (-3327 3825);
FORCEADD TAP..1
(-3325 3625);
FORCEPROP 3 LASTPIN (-3375 3625) SIG_NAME M_H_CPU0_SB_DQ<10>
J 0
(-3365 3635);
DISPLAY 0.659574 (-3365 3635);
PAINT MONO (-3365 3635);
DISPLAY INVISIBLE (-3365 3635);
FORCEPROP 1 LASTPIN (-3375 3625) BN 10
J 0
(-3387 3633);
DISPLAY 0.489362 (-3387 3633);
PAINT GREEN (-3387 3633);
FORCEPROP 2 LAST CDS_LIB mstr_standard
J 0
(-3325 3625);
DISPLAY 0.723404 (-3325 3625);
PAINT MONO (-3325 3625);
DISPLAY INVISIBLE (-3325 3625);
FORCEPROP 1 LAST BODY_TYPE PLUMBING
J 0
(-3325 3675);
DISPLAY 0.872340 (-3325 3675);
PAINT GREEN (-3325 3675);
DISPLAY INVISIBLE (-3325 3675);
FORCEPROP 1 LAST HDL_TAP TRUE
J 0
(-3000 3500);
DISPLAY 0.872340 (-3000 3500);
DISPLAY INVISIBLE (-3000 3500);
FORCEPROP 1 LAST PATH I205
J 0
(-3327 3625);
DISPLAY 0.872340 (-3327 3625);
PAINT GREEN (-3327 3625);
DISPLAY INVISIBLE (-3327 3625);
FORCEADD TAP..1
(-3325 3375);
FORCEPROP 3 LASTPIN (-3375 3375) SIG_NAME M_H_CPU0_SB_DQ<15>
J 0
(-3365 3385);
DISPLAY 0.659574 (-3365 3385);
PAINT MONO (-3365 3385);
DISPLAY INVISIBLE (-3365 3385);
FORCEPROP 1 LASTPIN (-3375 3375) BN 15
J 0
(-3387 3383);
DISPLAY 0.489362 (-3387 3383);
PAINT GREEN (-3387 3383);
FORCEPROP 2 LAST CDS_LIB mstr_standard
J 0
(-3325 3375);
DISPLAY 0.723404 (-3325 3375);
PAINT MONO (-3325 3375);
DISPLAY INVISIBLE (-3325 3375);
FORCEPROP 1 LAST BODY_TYPE PLUMBING
J 0
(-3325 3425);
DISPLAY 0.872340 (-3325 3425);
PAINT GREEN (-3325 3425);
DISPLAY INVISIBLE (-3325 3425);
FORCEPROP 1 LAST HDL_TAP TRUE
J 0
(-3000 3250);
DISPLAY 0.872340 (-3000 3250);
DISPLAY INVISIBLE (-3000 3250);
FORCEPROP 1 LAST PATH I206
J 0
(-3327 3375);
DISPLAY 0.872340 (-3327 3375);
PAINT GREEN (-3327 3375);
DISPLAY INVISIBLE (-3327 3375);
FORCEADD TAP..1
(-3325 3425);
FORCEPROP 3 LASTPIN (-3375 3425) SIG_NAME M_H_CPU0_SB_DQ<14>
J 0
(-3365 3435);
DISPLAY 0.659574 (-3365 3435);
PAINT MONO (-3365 3435);
DISPLAY INVISIBLE (-3365 3435);
FORCEPROP 1 LASTPIN (-3375 3425) BN 14
J 0
(-3387 3433);
DISPLAY 0.489362 (-3387 3433);
PAINT GREEN (-3387 3433);
FORCEPROP 2 LAST CDS_LIB mstr_standard
J 0
(-3325 3425);
DISPLAY 0.723404 (-3325 3425);
PAINT MONO (-3325 3425);
DISPLAY INVISIBLE (-3325 3425);
FORCEPROP 1 LAST BODY_TYPE PLUMBING
J 0
(-3325 3475);
DISPLAY 0.872340 (-3325 3475);
PAINT GREEN (-3325 3475);
DISPLAY INVISIBLE (-3325 3475);
FORCEPROP 1 LAST HDL_TAP TRUE
J 0
(-3000 3300);
DISPLAY 0.872340 (-3000 3300);
DISPLAY INVISIBLE (-3000 3300);
FORCEPROP 1 LAST PATH I207
J 0
(-3327 3425);
DISPLAY 0.872340 (-3327 3425);
PAINT GREEN (-3327 3425);
DISPLAY INVISIBLE (-3327 3425);
FORCEADD TAP..1
(-3325 3475);
FORCEPROP 3 LASTPIN (-3375 3475) SIG_NAME M_H_CPU0_SB_DQ<13>
J 0
(-3365 3485);
DISPLAY 0.659574 (-3365 3485);
PAINT MONO (-3365 3485);
DISPLAY INVISIBLE (-3365 3485);
FORCEPROP 1 LASTPIN (-3375 3475) BN 13
J 0
(-3387 3483);
DISPLAY 0.489362 (-3387 3483);
PAINT GREEN (-3387 3483);
FORCEPROP 2 LAST CDS_LIB mstr_standard
J 0
(-3325 3475);
DISPLAY 0.723404 (-3325 3475);
PAINT MONO (-3325 3475);
DISPLAY INVISIBLE (-3325 3475);
FORCEPROP 1 LAST BODY_TYPE PLUMBING
J 0
(-3325 3525);
DISPLAY 0.872340 (-3325 3525);
PAINT GREEN (-3325 3525);
DISPLAY INVISIBLE (-3325 3525);
FORCEPROP 1 LAST HDL_TAP TRUE
J 0
(-3000 3350);
DISPLAY 0.872340 (-3000 3350);
DISPLAY INVISIBLE (-3000 3350);
FORCEPROP 1 LAST PATH I208
J 0
(-3327 3475);
DISPLAY 0.872340 (-3327 3475);
PAINT GREEN (-3327 3475);
DISPLAY INVISIBLE (-3327 3475);
FORCEADD TAP..1
(-3325 3525);
FORCEPROP 3 LASTPIN (-3375 3525) SIG_NAME M_H_CPU0_SB_DQ<12>
J 0
(-3365 3535);
DISPLAY 0.659574 (-3365 3535);
PAINT MONO (-3365 3535);
DISPLAY INVISIBLE (-3365 3535);
FORCEPROP 1 LASTPIN (-3375 3525) BN 12
J 0
(-3387 3533);
DISPLAY 0.489362 (-3387 3533);
PAINT GREEN (-3387 3533);
FORCEPROP 2 LAST CDS_LIB mstr_standard
J 0
(-3325 3525);
DISPLAY 0.723404 (-3325 3525);
PAINT MONO (-3325 3525);
DISPLAY INVISIBLE (-3325 3525);
FORCEPROP 1 LAST BODY_TYPE PLUMBING
J 0
(-3325 3575);
DISPLAY 0.872340 (-3325 3575);
PAINT GREEN (-3325 3575);
DISPLAY INVISIBLE (-3325 3575);
FORCEPROP 1 LAST HDL_TAP TRUE
J 0
(-3000 3400);
DISPLAY 0.872340 (-3000 3400);
DISPLAY INVISIBLE (-3000 3400);
FORCEPROP 1 LAST PATH I209
J 0
(-3327 3525);
DISPLAY 0.872340 (-3327 3525);
PAINT GREEN (-3327 3525);
DISPLAY INVISIBLE (-3327 3525);
FORCEADD TAP..1
(-3325 3575);
FORCEPROP 3 LASTPIN (-3375 3575) SIG_NAME M_H_CPU0_SB_DQ<11>
J 0
(-3365 3585);
DISPLAY 0.659574 (-3365 3585);
PAINT MONO (-3365 3585);
DISPLAY INVISIBLE (-3365 3585);
FORCEPROP 1 LASTPIN (-3375 3575) BN 11
J 0
(-3387 3583);
DISPLAY 0.489362 (-3387 3583);
PAINT GREEN (-3387 3583);
FORCEPROP 2 LAST CDS_LIB mstr_standard
J 0
(-3325 3575);
DISPLAY 0.723404 (-3325 3575);
PAINT MONO (-3325 3575);
DISPLAY INVISIBLE (-3325 3575);
FORCEPROP 1 LAST BODY_TYPE PLUMBING
J 0
(-3325 3625);
DISPLAY 0.872340 (-3325 3625);
PAINT GREEN (-3325 3625);
DISPLAY INVISIBLE (-3325 3625);
FORCEPROP 1 LAST HDL_TAP TRUE
J 0
(-3000 3450);
DISPLAY 0.872340 (-3000 3450);
DISPLAY INVISIBLE (-3000 3450);
FORCEPROP 1 LAST PATH I210
J 0
(-3327 3575);
DISPLAY 0.872340 (-3327 3575);
PAINT GREEN (-3327 3575);
DISPLAY INVISIBLE (-3327 3575);
FORCEADD TAP..1
(-3325 3175);
FORCEPROP 3 LASTPIN (-3375 3175) SIG_NAME M_H_CPU0_SB_DQ<18>
J 0
(-3365 3185);
DISPLAY 0.659574 (-3365 3185);
PAINT MONO (-3365 3185);
DISPLAY INVISIBLE (-3365 3185);
FORCEPROP 1 LASTPIN (-3375 3175) BN 18
J 0
(-3387 3183);
DISPLAY 0.489362 (-3387 3183);
PAINT GREEN (-3387 3183);
FORCEPROP 2 LAST CDS_LIB mstr_standard
J 0
(-3325 3175);
DISPLAY 0.723404 (-3325 3175);
PAINT MONO (-3325 3175);
DISPLAY INVISIBLE (-3325 3175);
FORCEPROP 1 LAST BODY_TYPE PLUMBING
J 0
(-3325 3225);
DISPLAY 0.872340 (-3325 3225);
PAINT GREEN (-3325 3225);
DISPLAY INVISIBLE (-3325 3225);
FORCEPROP 1 LAST HDL_TAP TRUE
J 0
(-3000 3050);
DISPLAY 0.872340 (-3000 3050);
DISPLAY INVISIBLE (-3000 3050);
FORCEPROP 1 LAST PATH I211
J 0
(-3327 3175);
DISPLAY 0.872340 (-3327 3175);
PAINT GREEN (-3327 3175);
DISPLAY INVISIBLE (-3327 3175);
FORCEADD TAP..1
(-3325 3125);
FORCEPROP 3 LASTPIN (-3375 3125) SIG_NAME M_H_CPU0_SB_DQ<19>
J 0
(-3365 3135);
DISPLAY 0.659574 (-3365 3135);
PAINT MONO (-3365 3135);
DISPLAY INVISIBLE (-3365 3135);
FORCEPROP 1 LASTPIN (-3375 3125) BN 19
J 0
(-3387 3133);
DISPLAY 0.489362 (-3387 3133);
PAINT GREEN (-3387 3133);
FORCEPROP 2 LAST CDS_LIB mstr_standard
J 0
(-3325 3125);
DISPLAY 0.723404 (-3325 3125);
PAINT MONO (-3325 3125);
DISPLAY INVISIBLE (-3325 3125);
FORCEPROP 1 LAST BODY_TYPE PLUMBING
J 0
(-3325 3175);
DISPLAY 0.872340 (-3325 3175);
PAINT GREEN (-3325 3175);
DISPLAY INVISIBLE (-3325 3175);
FORCEPROP 1 LAST HDL_TAP TRUE
J 0
(-3000 3000);
DISPLAY 0.872340 (-3000 3000);
DISPLAY INVISIBLE (-3000 3000);
FORCEPROP 1 LAST PATH I212
J 0
(-3327 3125);
DISPLAY 0.872340 (-3327 3125);
PAINT GREEN (-3327 3125);
DISPLAY INVISIBLE (-3327 3125);
FORCEADD TAP..1
(-3325 3075);
FORCEPROP 3 LASTPIN (-3375 3075) SIG_NAME M_H_CPU0_SB_DQ<20>
J 0
(-3365 3085);
DISPLAY 0.659574 (-3365 3085);
PAINT MONO (-3365 3085);
DISPLAY INVISIBLE (-3365 3085);
FORCEPROP 1 LASTPIN (-3375 3075) BN 20
J 0
(-3387 3083);
DISPLAY 0.489362 (-3387 3083);
PAINT GREEN (-3387 3083);
FORCEPROP 2 LAST CDS_LIB mstr_standard
J 0
(-3325 3075);
DISPLAY 0.723404 (-3325 3075);
PAINT MONO (-3325 3075);
DISPLAY INVISIBLE (-3325 3075);
FORCEPROP 1 LAST BODY_TYPE PLUMBING
J 0
(-3325 3125);
DISPLAY 0.872340 (-3325 3125);
PAINT GREEN (-3325 3125);
DISPLAY INVISIBLE (-3325 3125);
FORCEPROP 1 LAST HDL_TAP TRUE
J 0
(-3000 2950);
DISPLAY 0.872340 (-3000 2950);
DISPLAY INVISIBLE (-3000 2950);
FORCEPROP 1 LAST PATH I213
J 0
(-3327 3075);
DISPLAY 0.872340 (-3327 3075);
PAINT GREEN (-3327 3075);
DISPLAY INVISIBLE (-3327 3075);
FORCEADD TAP..1
(-3325 3275);
FORCEPROP 3 LASTPIN (-3375 3275) SIG_NAME M_H_CPU0_SB_DQ<16>
J 0
(-3365 3285);
DISPLAY 0.659574 (-3365 3285);
PAINT MONO (-3365 3285);
DISPLAY INVISIBLE (-3365 3285);
FORCEPROP 1 LASTPIN (-3375 3275) BN 16
J 0
(-3387 3283);
DISPLAY 0.489362 (-3387 3283);
PAINT GREEN (-3387 3283);
FORCEPROP 2 LAST CDS_LIB mstr_standard
J 0
(-3325 3275);
DISPLAY 0.723404 (-3325 3275);
PAINT MONO (-3325 3275);
DISPLAY INVISIBLE (-3325 3275);
FORCEPROP 1 LAST BODY_TYPE PLUMBING
J 0
(-3325 3325);
DISPLAY 0.872340 (-3325 3325);
PAINT GREEN (-3325 3325);
DISPLAY INVISIBLE (-3325 3325);
FORCEPROP 1 LAST HDL_TAP TRUE
J 0
(-3000 3150);
DISPLAY 0.872340 (-3000 3150);
DISPLAY INVISIBLE (-3000 3150);
FORCEPROP 1 LAST PATH I214
J 0
(-3327 3275);
DISPLAY 0.872340 (-3327 3275);
PAINT GREEN (-3327 3275);
DISPLAY INVISIBLE (-3327 3275);
FORCEADD TAP..1
(-3325 3225);
FORCEPROP 3 LASTPIN (-3375 3225) SIG_NAME M_H_CPU0_SB_DQ<17>
J 0
(-3365 3235);
DISPLAY 0.659574 (-3365 3235);
PAINT MONO (-3365 3235);
DISPLAY INVISIBLE (-3365 3235);
FORCEPROP 1 LASTPIN (-3375 3225) BN 17
J 0
(-3387 3233);
DISPLAY 0.489362 (-3387 3233);
PAINT GREEN (-3387 3233);
FORCEPROP 2 LAST CDS_LIB mstr_standard
J 0
(-3325 3225);
DISPLAY 0.723404 (-3325 3225);
PAINT MONO (-3325 3225);
DISPLAY INVISIBLE (-3325 3225);
FORCEPROP 1 LAST BODY_TYPE PLUMBING
J 0
(-3325 3275);
DISPLAY 0.872340 (-3325 3275);
PAINT GREEN (-3325 3275);
DISPLAY INVISIBLE (-3325 3275);
FORCEPROP 1 LAST HDL_TAP TRUE
J 0
(-3000 3100);
DISPLAY 0.872340 (-3000 3100);
DISPLAY INVISIBLE (-3000 3100);
FORCEPROP 1 LAST PATH I215
J 0
(-3327 3225);
DISPLAY 0.872340 (-3327 3225);
PAINT GREEN (-3327 3225);
DISPLAY INVISIBLE (-3327 3225);
FORCEADD TAP..1
(-3325 2975);
FORCEPROP 3 LASTPIN (-3375 2975) SIG_NAME M_H_CPU0_SB_DQ<22>
J 0
(-3365 2985);
DISPLAY 0.659574 (-3365 2985);
PAINT MONO (-3365 2985);
DISPLAY INVISIBLE (-3365 2985);
FORCEPROP 1 LASTPIN (-3375 2975) BN 22
J 0
(-3387 2983);
DISPLAY 0.489362 (-3387 2983);
PAINT GREEN (-3387 2983);
FORCEPROP 2 LAST CDS_LIB mstr_standard
J 0
(-3325 2975);
DISPLAY 0.723404 (-3325 2975);
PAINT MONO (-3325 2975);
DISPLAY INVISIBLE (-3325 2975);
FORCEPROP 1 LAST BODY_TYPE PLUMBING
J 0
(-3325 3025);
DISPLAY 0.872340 (-3325 3025);
PAINT GREEN (-3325 3025);
DISPLAY INVISIBLE (-3325 3025);
FORCEPROP 1 LAST HDL_TAP TRUE
J 0
(-3000 2850);
DISPLAY 0.872340 (-3000 2850);
DISPLAY INVISIBLE (-3000 2850);
FORCEPROP 1 LAST PATH I216
J 0
(-3327 2975);
DISPLAY 0.872340 (-3327 2975);
PAINT GREEN (-3327 2975);
DISPLAY INVISIBLE (-3327 2975);
FORCEADD TAP..1
(-3325 2925);
FORCEPROP 3 LASTPIN (-3375 2925) SIG_NAME M_H_CPU0_SB_DQ<23>
J 0
(-3365 2935);
DISPLAY 0.659574 (-3365 2935);
PAINT MONO (-3365 2935);
DISPLAY INVISIBLE (-3365 2935);
FORCEPROP 1 LASTPIN (-3375 2925) BN 23
J 0
(-3387 2933);
DISPLAY 0.489362 (-3387 2933);
PAINT GREEN (-3387 2933);
FORCEPROP 2 LAST CDS_LIB mstr_standard
J 0
(-3325 2925);
DISPLAY 0.723404 (-3325 2925);
PAINT MONO (-3325 2925);
DISPLAY INVISIBLE (-3325 2925);
FORCEPROP 1 LAST BODY_TYPE PLUMBING
J 0
(-3325 2975);
DISPLAY 0.872340 (-3325 2975);
PAINT GREEN (-3325 2975);
DISPLAY INVISIBLE (-3325 2975);
FORCEPROP 1 LAST HDL_TAP TRUE
J 0
(-3000 2800);
DISPLAY 0.872340 (-3000 2800);
DISPLAY INVISIBLE (-3000 2800);
FORCEPROP 1 LAST PATH I217
J 0
(-3327 2925);
DISPLAY 0.872340 (-3327 2925);
PAINT GREEN (-3327 2925);
DISPLAY INVISIBLE (-3327 2925);
FORCEADD TAP..1
(-3325 3025);
FORCEPROP 3 LASTPIN (-3375 3025) SIG_NAME M_H_CPU0_SB_DQ<21>
J 0
(-3365 3035);
DISPLAY 0.659574 (-3365 3035);
PAINT MONO (-3365 3035);
DISPLAY INVISIBLE (-3365 3035);
FORCEPROP 1 LASTPIN (-3375 3025) BN 21
J 0
(-3387 3033);
DISPLAY 0.489362 (-3387 3033);
PAINT GREEN (-3387 3033);
FORCEPROP 2 LAST CDS_LIB mstr_standard
J 0
(-3325 3025);
DISPLAY 0.723404 (-3325 3025);
PAINT MONO (-3325 3025);
DISPLAY INVISIBLE (-3325 3025);
FORCEPROP 1 LAST BODY_TYPE PLUMBING
J 0
(-3325 3075);
DISPLAY 0.872340 (-3325 3075);
PAINT GREEN (-3325 3075);
DISPLAY INVISIBLE (-3325 3075);
FORCEPROP 1 LAST HDL_TAP TRUE
J 0
(-3000 2900);
DISPLAY 0.872340 (-3000 2900);
DISPLAY INVISIBLE (-3000 2900);
FORCEPROP 1 LAST PATH I218
J 0
(-3327 3025);
DISPLAY 0.872340 (-3327 3025);
PAINT GREEN (-3327 3025);
DISPLAY INVISIBLE (-3327 3025);
FORCEADD TAP..1
(-3325 2825);
FORCEPROP 3 LASTPIN (-3375 2825) SIG_NAME M_H_CPU0_SB_DQ<24>
J 0
(-3365 2835);
DISPLAY 0.659574 (-3365 2835);
PAINT MONO (-3365 2835);
DISPLAY INVISIBLE (-3365 2835);
FORCEPROP 1 LASTPIN (-3375 2825) BN 24
J 0
(-3387 2833);
DISPLAY 0.489362 (-3387 2833);
PAINT GREEN (-3387 2833);
FORCEPROP 2 LAST CDS_LIB mstr_standard
J 0
(-3325 2825);
DISPLAY 0.723404 (-3325 2825);
PAINT MONO (-3325 2825);
DISPLAY INVISIBLE (-3325 2825);
FORCEPROP 1 LAST BODY_TYPE PLUMBING
J 0
(-3325 2875);
DISPLAY 0.872340 (-3325 2875);
PAINT GREEN (-3325 2875);
DISPLAY INVISIBLE (-3325 2875);
FORCEPROP 1 LAST HDL_TAP TRUE
J 0
(-3000 2700);
DISPLAY 0.872340 (-3000 2700);
DISPLAY INVISIBLE (-3000 2700);
FORCEPROP 1 LAST PATH I219
J 0
(-3327 2825);
DISPLAY 0.872340 (-3327 2825);
PAINT GREEN (-3327 2825);
DISPLAY INVISIBLE (-3327 2825);
FORCEADD TAP..1
(-3325 2675);
FORCEPROP 3 LASTPIN (-3375 2675) SIG_NAME M_H_CPU0_SB_DQ<27>
J 0
(-3365 2685);
DISPLAY 0.659574 (-3365 2685);
PAINT MONO (-3365 2685);
DISPLAY INVISIBLE (-3365 2685);
FORCEPROP 1 LASTPIN (-3375 2675) BN 27
J 0
(-3387 2683);
DISPLAY 0.489362 (-3387 2683);
PAINT GREEN (-3387 2683);
FORCEPROP 2 LAST CDS_LIB mstr_standard
J 0
(-3325 2675);
DISPLAY 0.723404 (-3325 2675);
PAINT MONO (-3325 2675);
DISPLAY INVISIBLE (-3325 2675);
FORCEPROP 1 LAST BODY_TYPE PLUMBING
J 0
(-3325 2725);
DISPLAY 0.872340 (-3325 2725);
PAINT GREEN (-3325 2725);
DISPLAY INVISIBLE (-3325 2725);
FORCEPROP 1 LAST HDL_TAP TRUE
J 0
(-3000 2550);
DISPLAY 0.872340 (-3000 2550);
DISPLAY INVISIBLE (-3000 2550);
FORCEPROP 1 LAST PATH I220
J 0
(-3327 2675);
DISPLAY 0.872340 (-3327 2675);
PAINT GREEN (-3327 2675);
DISPLAY INVISIBLE (-3327 2675);
FORCEADD TAP..1
(-3325 2625);
FORCEPROP 3 LASTPIN (-3375 2625) SIG_NAME M_H_CPU0_SB_DQ<28>
J 0
(-3365 2635);
DISPLAY 0.659574 (-3365 2635);
PAINT MONO (-3365 2635);
DISPLAY INVISIBLE (-3365 2635);
FORCEPROP 1 LASTPIN (-3375 2625) BN 28
J 0
(-3387 2633);
DISPLAY 0.489362 (-3387 2633);
PAINT GREEN (-3387 2633);
FORCEPROP 2 LAST CDS_LIB mstr_standard
J 0
(-3325 2625);
DISPLAY 0.723404 (-3325 2625);
PAINT MONO (-3325 2625);
DISPLAY INVISIBLE (-3325 2625);
FORCEPROP 1 LAST BODY_TYPE PLUMBING
J 0
(-3325 2675);
DISPLAY 0.872340 (-3325 2675);
PAINT GREEN (-3325 2675);
DISPLAY INVISIBLE (-3325 2675);
FORCEPROP 1 LAST HDL_TAP TRUE
J 0
(-3000 2500);
DISPLAY 0.872340 (-3000 2500);
DISPLAY INVISIBLE (-3000 2500);
FORCEPROP 1 LAST PATH I221
J 0
(-3327 2625);
DISPLAY 0.872340 (-3327 2625);
PAINT GREEN (-3327 2625);
DISPLAY INVISIBLE (-3327 2625);
FORCEADD TAP..1
(-3325 2575);
FORCEPROP 3 LASTPIN (-3375 2575) SIG_NAME M_H_CPU0_SB_DQ<29>
J 0
(-3365 2585);
DISPLAY 0.659574 (-3365 2585);
PAINT MONO (-3365 2585);
DISPLAY INVISIBLE (-3365 2585);
FORCEPROP 1 LASTPIN (-3375 2575) BN 29
J 0
(-3387 2583);
DISPLAY 0.489362 (-3387 2583);
PAINT GREEN (-3387 2583);
FORCEPROP 2 LAST CDS_LIB mstr_standard
J 0
(-3325 2575);
DISPLAY 0.723404 (-3325 2575);
PAINT MONO (-3325 2575);
DISPLAY INVISIBLE (-3325 2575);
FORCEPROP 1 LAST BODY_TYPE PLUMBING
J 0
(-3325 2625);
DISPLAY 0.872340 (-3325 2625);
PAINT GREEN (-3325 2625);
DISPLAY INVISIBLE (-3325 2625);
FORCEPROP 1 LAST HDL_TAP TRUE
J 0
(-3000 2450);
DISPLAY 0.872340 (-3000 2450);
DISPLAY INVISIBLE (-3000 2450);
FORCEPROP 1 LAST PATH I222
J 0
(-3327 2575);
DISPLAY 0.872340 (-3327 2575);
PAINT GREEN (-3327 2575);
DISPLAY INVISIBLE (-3327 2575);
FORCEADD TAP..1
(-3325 2775);
FORCEPROP 3 LASTPIN (-3375 2775) SIG_NAME M_H_CPU0_SB_DQ<25>
J 0
(-3365 2785);
DISPLAY 0.659574 (-3365 2785);
PAINT MONO (-3365 2785);
DISPLAY INVISIBLE (-3365 2785);
FORCEPROP 1 LASTPIN (-3375 2775) BN 25
J 0
(-3387 2783);
DISPLAY 0.489362 (-3387 2783);
PAINT GREEN (-3387 2783);
FORCEPROP 2 LAST CDS_LIB mstr_standard
J 0
(-3325 2775);
DISPLAY 0.723404 (-3325 2775);
PAINT MONO (-3325 2775);
DISPLAY INVISIBLE (-3325 2775);
FORCEPROP 1 LAST BODY_TYPE PLUMBING
J 0
(-3325 2825);
DISPLAY 0.872340 (-3325 2825);
PAINT GREEN (-3325 2825);
DISPLAY INVISIBLE (-3325 2825);
FORCEPROP 1 LAST HDL_TAP TRUE
J 0
(-3000 2650);
DISPLAY 0.872340 (-3000 2650);
DISPLAY INVISIBLE (-3000 2650);
FORCEPROP 1 LAST PATH I223
J 0
(-3327 2775);
DISPLAY 0.872340 (-3327 2775);
PAINT GREEN (-3327 2775);
DISPLAY INVISIBLE (-3327 2775);
FORCEADD TAP..1
(-3325 2725);
FORCEPROP 3 LASTPIN (-3375 2725) SIG_NAME M_H_CPU0_SB_DQ<26>
J 0
(-3365 2735);
DISPLAY 0.659574 (-3365 2735);
PAINT MONO (-3365 2735);
DISPLAY INVISIBLE (-3365 2735);
FORCEPROP 1 LASTPIN (-3375 2725) BN 26
J 0
(-3387 2733);
DISPLAY 0.489362 (-3387 2733);
PAINT GREEN (-3387 2733);
FORCEPROP 2 LAST CDS_LIB mstr_standard
J 0
(-3325 2725);
DISPLAY 0.723404 (-3325 2725);
PAINT MONO (-3325 2725);
DISPLAY INVISIBLE (-3325 2725);
FORCEPROP 1 LAST BODY_TYPE PLUMBING
J 0
(-3325 2775);
DISPLAY 0.872340 (-3325 2775);
PAINT GREEN (-3325 2775);
DISPLAY INVISIBLE (-3325 2775);
FORCEPROP 1 LAST HDL_TAP TRUE
J 0
(-3000 2600);
DISPLAY 0.872340 (-3000 2600);
DISPLAY INVISIBLE (-3000 2600);
FORCEPROP 1 LAST PATH I224
J 0
(-3327 2725);
DISPLAY 0.872340 (-3327 2725);
PAINT GREEN (-3327 2725);
DISPLAY INVISIBLE (-3327 2725);
FORCEADD TAP..1
(-3325 2375);
FORCEPROP 3 LASTPIN (-3375 2375) SIG_NAME M_H_CPU0_SA_CB<0>
J 0
(-3365 2385);
DISPLAY 0.659574 (-3365 2385);
PAINT MONO (-3365 2385);
DISPLAY INVISIBLE (-3365 2385);
FORCEPROP 1 LASTPIN (-3375 2375) BN 0
J 0
(-3387 2383);
DISPLAY 0.489362 (-3387 2383);
PAINT GREEN (-3387 2383);
FORCEPROP 2 LAST CDS_LIB mstr_standard
J 2
(-3325 2375);
DISPLAY 0.723404 (-3325 2375);
PAINT MONO (-3325 2375);
DISPLAY INVISIBLE (-3325 2375);
FORCEPROP 1 LAST BODY_TYPE PLUMBING
J 0
(-3325 2425);
DISPLAY 0.872340 (-3325 2425);
PAINT GREEN (-3325 2425);
DISPLAY INVISIBLE (-3325 2425);
FORCEPROP 1 LAST HDL_TAP TRUE
J 0
(-3000 2250);
DISPLAY 0.872340 (-3000 2250);
DISPLAY INVISIBLE (-3000 2250);
FORCEPROP 1 LAST PATH I225
J 0
(-3327 2375);
DISPLAY 0.872340 (-3327 2375);
PAINT GREEN (-3327 2375);
DISPLAY INVISIBLE (-3327 2375);
FORCEADD TAP..1
(-3325 2325);
FORCEPROP 3 LASTPIN (-3375 2325) SIG_NAME M_H_CPU0_SA_CB<1>
J 0
(-3365 2335);
DISPLAY 0.659574 (-3365 2335);
PAINT MONO (-3365 2335);
DISPLAY INVISIBLE (-3365 2335);
FORCEPROP 1 LASTPIN (-3375 2325) BN 1
J 0
(-3387 2333);
DISPLAY 0.489362 (-3387 2333);
PAINT GREEN (-3387 2333);
FORCEPROP 2 LAST CDS_LIB mstr_standard
J 2
(-3325 2325);
DISPLAY 0.723404 (-3325 2325);
PAINT MONO (-3325 2325);
DISPLAY INVISIBLE (-3325 2325);
FORCEPROP 1 LAST BODY_TYPE PLUMBING
J 0
(-3325 2375);
DISPLAY 0.872340 (-3325 2375);
PAINT GREEN (-3325 2375);
DISPLAY INVISIBLE (-3325 2375);
FORCEPROP 1 LAST HDL_TAP TRUE
J 0
(-3000 2200);
DISPLAY 0.872340 (-3000 2200);
DISPLAY INVISIBLE (-3000 2200);
FORCEPROP 1 LAST PATH I226
J 0
(-3327 2325);
DISPLAY 0.872340 (-3327 2325);
PAINT GREEN (-3327 2325);
DISPLAY INVISIBLE (-3327 2325);
FORCEADD TAP..1
(-3325 2525);
FORCEPROP 3 LASTPIN (-3375 2525) SIG_NAME M_H_CPU0_SB_DQ<30>
J 0
(-3365 2535);
DISPLAY 0.659574 (-3365 2535);
PAINT MONO (-3365 2535);
DISPLAY INVISIBLE (-3365 2535);
FORCEPROP 1 LASTPIN (-3375 2525) BN 30
J 0
(-3387 2533);
DISPLAY 0.489362 (-3387 2533);
PAINT GREEN (-3387 2533);
FORCEPROP 2 LAST CDS_LIB mstr_standard
J 0
(-3325 2525);
DISPLAY 0.723404 (-3325 2525);
PAINT MONO (-3325 2525);
DISPLAY INVISIBLE (-3325 2525);
FORCEPROP 1 LAST BODY_TYPE PLUMBING
J 0
(-3325 2575);
DISPLAY 0.872340 (-3325 2575);
PAINT GREEN (-3325 2575);
DISPLAY INVISIBLE (-3325 2575);
FORCEPROP 1 LAST HDL_TAP TRUE
J 0
(-3000 2400);
DISPLAY 0.872340 (-3000 2400);
DISPLAY INVISIBLE (-3000 2400);
FORCEPROP 1 LAST PATH I227
J 0
(-3327 2525);
DISPLAY 0.872340 (-3327 2525);
PAINT GREEN (-3327 2525);
DISPLAY INVISIBLE (-3327 2525);
FORCEADD TAP..1
(-3325 2475);
FORCEPROP 3 LASTPIN (-3375 2475) SIG_NAME M_H_CPU0_SB_DQ<31>
J 0
(-3365 2485);
DISPLAY 0.659574 (-3365 2485);
PAINT MONO (-3365 2485);
DISPLAY INVISIBLE (-3365 2485);
FORCEPROP 1 LASTPIN (-3375 2475) BN 31
J 0
(-3387 2483);
DISPLAY 0.489362 (-3387 2483);
PAINT GREEN (-3387 2483);
FORCEPROP 2 LAST CDS_LIB mstr_standard
J 0
(-3325 2475);
DISPLAY 0.723404 (-3325 2475);
PAINT MONO (-3325 2475);
DISPLAY INVISIBLE (-3325 2475);
FORCEPROP 1 LAST BODY_TYPE PLUMBING
J 0
(-3325 2525);
DISPLAY 0.872340 (-3325 2525);
PAINT GREEN (-3325 2525);
DISPLAY INVISIBLE (-3325 2525);
FORCEPROP 1 LAST HDL_TAP TRUE
J 0
(-3000 2350);
DISPLAY 0.872340 (-3000 2350);
DISPLAY INVISIBLE (-3000 2350);
FORCEPROP 1 LAST PATH I228
J 0
(-3327 2475);
DISPLAY 0.872340 (-3327 2475);
PAINT GREEN (-3327 2475);
DISPLAY INVISIBLE (-3327 2475);
FORCEADD TAP..1
(-3325 2225);
FORCEPROP 3 LASTPIN (-3375 2225) SIG_NAME M_H_CPU0_SA_CB<3>
J 0
(-3365 2235);
DISPLAY 0.659574 (-3365 2235);
PAINT MONO (-3365 2235);
DISPLAY INVISIBLE (-3365 2235);
FORCEPROP 1 LASTPIN (-3375 2225) BN 3
J 0
(-3387 2233);
DISPLAY 0.489362 (-3387 2233);
PAINT GREEN (-3387 2233);
FORCEPROP 2 LAST CDS_LIB mstr_standard
J 2
(-3325 2225);
DISPLAY 0.723404 (-3325 2225);
PAINT MONO (-3325 2225);
DISPLAY INVISIBLE (-3325 2225);
FORCEPROP 1 LAST BODY_TYPE PLUMBING
J 0
(-3325 2275);
DISPLAY 0.872340 (-3325 2275);
PAINT GREEN (-3325 2275);
DISPLAY INVISIBLE (-3325 2275);
FORCEPROP 1 LAST HDL_TAP TRUE
J 0
(-3000 2100);
DISPLAY 0.872340 (-3000 2100);
DISPLAY INVISIBLE (-3000 2100);
FORCEPROP 1 LAST PATH I229
J 0
(-3327 2225);
DISPLAY 0.872340 (-3327 2225);
PAINT GREEN (-3327 2225);
DISPLAY INVISIBLE (-3327 2225);
FORCEADD TAP..1
(-3325 2275);
FORCEPROP 3 LASTPIN (-3375 2275) SIG_NAME M_H_CPU0_SA_CB<2>
J 0
(-3365 2285);
DISPLAY 0.659574 (-3365 2285);
PAINT MONO (-3365 2285);
DISPLAY INVISIBLE (-3365 2285);
FORCEPROP 1 LASTPIN (-3375 2275) BN 2
J 0
(-3387 2283);
DISPLAY 0.489362 (-3387 2283);
PAINT GREEN (-3387 2283);
FORCEPROP 2 LAST CDS_LIB mstr_standard
J 2
(-3325 2275);
DISPLAY 0.723404 (-3325 2275);
PAINT MONO (-3325 2275);
DISPLAY INVISIBLE (-3325 2275);
FORCEPROP 1 LAST BODY_TYPE PLUMBING
J 0
(-3325 2325);
DISPLAY 0.872340 (-3325 2325);
PAINT GREEN (-3325 2325);
DISPLAY INVISIBLE (-3325 2325);
FORCEPROP 1 LAST HDL_TAP TRUE
J 0
(-3000 2150);
DISPLAY 0.872340 (-3000 2150);
DISPLAY INVISIBLE (-3000 2150);
FORCEPROP 1 LAST PATH I230
J 0
(-3327 2275);
DISPLAY 0.872340 (-3327 2275);
PAINT GREEN (-3327 2275);
DISPLAY INVISIBLE (-3327 2275);
FORCEADD TAP..1
(-3325 2075);
FORCEPROP 3 LASTPIN (-3375 2075) SIG_NAME M_H_CPU0_SA_CB<6>
J 0
(-3365 2085);
DISPLAY 0.659574 (-3365 2085);
PAINT MONO (-3365 2085);
DISPLAY INVISIBLE (-3365 2085);
FORCEPROP 1 LASTPIN (-3375 2075) BN 6
J 0
(-3387 2083);
DISPLAY 0.489362 (-3387 2083);
PAINT GREEN (-3387 2083);
FORCEPROP 2 LAST CDS_LIB mstr_standard
J 2
(-3325 2075);
DISPLAY 0.723404 (-3325 2075);
PAINT MONO (-3325 2075);
DISPLAY INVISIBLE (-3325 2075);
FORCEPROP 1 LAST BODY_TYPE PLUMBING
J 0
(-3325 2125);
DISPLAY 0.872340 (-3325 2125);
PAINT GREEN (-3325 2125);
DISPLAY INVISIBLE (-3325 2125);
FORCEPROP 1 LAST HDL_TAP TRUE
J 0
(-3000 1950);
DISPLAY 0.872340 (-3000 1950);
DISPLAY INVISIBLE (-3000 1950);
FORCEPROP 1 LAST PATH I231
J 0
(-3327 2075);
DISPLAY 0.872340 (-3327 2075);
PAINT GREEN (-3327 2075);
DISPLAY INVISIBLE (-3327 2075);
FORCEADD TAP..1
(-3325 2125);
FORCEPROP 3 LASTPIN (-3375 2125) SIG_NAME M_H_CPU0_SA_CB<5>
J 0
(-3365 2135);
DISPLAY 0.659574 (-3365 2135);
PAINT MONO (-3365 2135);
DISPLAY INVISIBLE (-3365 2135);
FORCEPROP 1 LASTPIN (-3375 2125) BN 5
J 0
(-3387 2133);
DISPLAY 0.489362 (-3387 2133);
PAINT GREEN (-3387 2133);
FORCEPROP 2 LAST CDS_LIB mstr_standard
J 2
(-3325 2125);
DISPLAY 0.723404 (-3325 2125);
PAINT MONO (-3325 2125);
DISPLAY INVISIBLE (-3325 2125);
FORCEPROP 1 LAST BODY_TYPE PLUMBING
J 0
(-3325 2175);
DISPLAY 0.872340 (-3325 2175);
PAINT GREEN (-3325 2175);
DISPLAY INVISIBLE (-3325 2175);
FORCEPROP 1 LAST HDL_TAP TRUE
J 0
(-3000 2000);
DISPLAY 0.872340 (-3000 2000);
DISPLAY INVISIBLE (-3000 2000);
FORCEPROP 1 LAST PATH I232
J 0
(-3327 2125);
DISPLAY 0.872340 (-3327 2125);
PAINT GREEN (-3327 2125);
DISPLAY INVISIBLE (-3327 2125);
FORCEADD TAP..1
(-3325 2175);
FORCEPROP 3 LASTPIN (-3375 2175) SIG_NAME M_H_CPU0_SA_CB<4>
J 0
(-3365 2185);
DISPLAY 0.659574 (-3365 2185);
PAINT MONO (-3365 2185);
DISPLAY INVISIBLE (-3365 2185);
FORCEPROP 1 LASTPIN (-3375 2175) BN 4
J 0
(-3387 2183);
DISPLAY 0.489362 (-3387 2183);
PAINT GREEN (-3387 2183);
FORCEPROP 2 LAST CDS_LIB mstr_standard
J 2
(-3325 2175);
DISPLAY 0.723404 (-3325 2175);
PAINT MONO (-3325 2175);
DISPLAY INVISIBLE (-3325 2175);
FORCEPROP 1 LAST BODY_TYPE PLUMBING
J 0
(-3325 2225);
DISPLAY 0.872340 (-3325 2225);
PAINT GREEN (-3325 2225);
DISPLAY INVISIBLE (-3325 2225);
FORCEPROP 1 LAST HDL_TAP TRUE
J 0
(-3000 2050);
DISPLAY 0.872340 (-3000 2050);
DISPLAY INVISIBLE (-3000 2050);
FORCEPROP 1 LAST PATH I233
J 0
(-3327 2175);
DISPLAY 0.872340 (-3327 2175);
PAINT GREEN (-3327 2175);
DISPLAY INVISIBLE (-3327 2175);
FORCEADD OFFPAGE..6
R 2
(-2725 1975);
FORCEPROP 2 LAST $XR0 93 
J 0
(-2511 1975);
DISPLAY 0.638298 (-2511 1975);
PAINT MONO (-2511 1975);
FORCEPROP 2 LAST CDS_LIB mstr_standard
J 2
(-2725 1975);
DISPLAY 0.723404 (-2725 1975);
PAINT MONO (-2725 1975);
DISPLAY INVISIBLE (-2725 1975);
FORCEPROP 1 LAST OFFPAGE TRUE
J 2
(-3050 1850);
DISPLAY 0.872340 (-3050 1850);
PAINT GREEN (-3050 1850);
DISPLAY INVISIBLE (-3050 1850);
FORCEPROP 1 LAST COMMENT_BODY TRUE
J 2
(-2825 1900);
DISPLAY 0.872340 (-2825 1900);
PAINT GREEN (-2825 1900);
DISPLAY INVISIBLE (-2825 1900);
FORCEPROP 2 LAST PATH I234
J 0
(-2500 2025);
DISPLAY 1.021277 (-2500 2025);
DISPLAY INVISIBLE (-2500 2025);
FORCEADD TAP..1
(-3325 1875);
FORCEPROP 3 LASTPIN (-3375 1875) SIG_NAME M_H_CPU0_SB_CB<1>
J 0
(-3365 1885);
DISPLAY 0.659574 (-3365 1885);
PAINT MONO (-3365 1885);
DISPLAY INVISIBLE (-3365 1885);
FORCEPROP 1 LASTPIN (-3375 1875) BN 1
J 0
(-3387 1883);
DISPLAY 0.489362 (-3387 1883);
PAINT GREEN (-3387 1883);
FORCEPROP 2 LAST CDS_LIB mstr_standard
J 2
(-3325 1875);
DISPLAY 0.723404 (-3325 1875);
PAINT MONO (-3325 1875);
DISPLAY INVISIBLE (-3325 1875);
FORCEPROP 1 LAST BODY_TYPE PLUMBING
J 0
(-3325 1925);
DISPLAY 0.872340 (-3325 1925);
PAINT GREEN (-3325 1925);
DISPLAY INVISIBLE (-3325 1925);
FORCEPROP 1 LAST HDL_TAP TRUE
J 0
(-3000 1750);
DISPLAY 0.872340 (-3000 1750);
DISPLAY INVISIBLE (-3000 1750);
FORCEPROP 1 LAST PATH I235
J 0
(-3327 1875);
DISPLAY 0.872340 (-3327 1875);
PAINT GREEN (-3327 1875);
DISPLAY INVISIBLE (-3327 1875);
FORCEADD TAP..1
(-3325 1925);
FORCEPROP 3 LASTPIN (-3375 1925) SIG_NAME M_H_CPU0_SB_CB<0>
J 0
(-3365 1935);
DISPLAY 0.659574 (-3365 1935);
PAINT MONO (-3365 1935);
DISPLAY INVISIBLE (-3365 1935);
FORCEPROP 1 LASTPIN (-3375 1925) BN 0
J 0
(-3387 1933);
DISPLAY 0.489362 (-3387 1933);
PAINT GREEN (-3387 1933);
FORCEPROP 2 LAST CDS_LIB mstr_standard
J 2
(-3325 1925);
DISPLAY 0.723404 (-3325 1925);
PAINT MONO (-3325 1925);
DISPLAY INVISIBLE (-3325 1925);
FORCEPROP 1 LAST BODY_TYPE PLUMBING
J 0
(-3325 1975);
DISPLAY 0.872340 (-3325 1975);
PAINT GREEN (-3325 1975);
DISPLAY INVISIBLE (-3325 1975);
FORCEPROP 1 LAST HDL_TAP TRUE
J 0
(-3000 1800);
DISPLAY 0.872340 (-3000 1800);
DISPLAY INVISIBLE (-3000 1800);
FORCEPROP 1 LAST PATH I236
J 0
(-3327 1925);
DISPLAY 0.872340 (-3327 1925);
PAINT GREEN (-3327 1925);
DISPLAY INVISIBLE (-3327 1925);
FORCEADD TAP..1
(-3325 2025);
FORCEPROP 3 LASTPIN (-3375 2025) SIG_NAME M_H_CPU0_SA_CB<7>
J 0
(-3365 2035);
DISPLAY 0.659574 (-3365 2035);
PAINT MONO (-3365 2035);
DISPLAY INVISIBLE (-3365 2035);
FORCEPROP 1 LASTPIN (-3375 2025) BN 7
J 0
(-3387 2033);
DISPLAY 0.489362 (-3387 2033);
PAINT GREEN (-3387 2033);
FORCEPROP 2 LAST CDS_LIB mstr_standard
J 2
(-3325 2025);
DISPLAY 0.723404 (-3325 2025);
PAINT MONO (-3325 2025);
DISPLAY INVISIBLE (-3325 2025);
FORCEPROP 1 LAST BODY_TYPE PLUMBING
J 0
(-3325 2075);
DISPLAY 0.872340 (-3325 2075);
PAINT GREEN (-3325 2075);
DISPLAY INVISIBLE (-3325 2075);
FORCEPROP 1 LAST HDL_TAP TRUE
J 0
(-3000 1900);
DISPLAY 0.872340 (-3000 1900);
DISPLAY INVISIBLE (-3000 1900);
FORCEPROP 1 LAST PATH I237
J 0
(-3327 2025);
DISPLAY 0.872340 (-3327 2025);
PAINT GREEN (-3327 2025);
DISPLAY INVISIBLE (-3327 2025);
FORCEADD TAP..1
(-3325 1825);
FORCEPROP 3 LASTPIN (-3375 1825) SIG_NAME M_H_CPU0_SB_CB<2>
J 0
(-3365 1835);
DISPLAY 0.659574 (-3365 1835);
PAINT MONO (-3365 1835);
DISPLAY INVISIBLE (-3365 1835);
FORCEPROP 1 LASTPIN (-3375 1825) BN 2
J 0
(-3387 1833);
DISPLAY 0.489362 (-3387 1833);
PAINT GREEN (-3387 1833);
FORCEPROP 2 LAST CDS_LIB mstr_standard
J 2
(-3325 1825);
DISPLAY 0.723404 (-3325 1825);
PAINT MONO (-3325 1825);
DISPLAY INVISIBLE (-3325 1825);
FORCEPROP 1 LAST BODY_TYPE PLUMBING
J 0
(-3325 1875);
DISPLAY 0.872340 (-3325 1875);
PAINT GREEN (-3325 1875);
DISPLAY INVISIBLE (-3325 1875);
FORCEPROP 1 LAST HDL_TAP TRUE
J 0
(-3000 1700);
DISPLAY 0.872340 (-3000 1700);
DISPLAY INVISIBLE (-3000 1700);
FORCEPROP 1 LAST PATH I238
J 0
(-3327 1825);
DISPLAY 0.872340 (-3327 1825);
PAINT GREEN (-3327 1825);
DISPLAY INVISIBLE (-3327 1825);
FORCEADD TAP..1
(-3325 1775);
FORCEPROP 3 LASTPIN (-3375 1775) SIG_NAME M_H_CPU0_SB_CB<3>
J 0
(-3365 1785);
DISPLAY 0.659574 (-3365 1785);
PAINT MONO (-3365 1785);
DISPLAY INVISIBLE (-3365 1785);
FORCEPROP 1 LASTPIN (-3375 1775) BN 3
J 0
(-3387 1783);
DISPLAY 0.489362 (-3387 1783);
PAINT GREEN (-3387 1783);
FORCEPROP 2 LAST CDS_LIB mstr_standard
J 2
(-3325 1775);
DISPLAY 0.723404 (-3325 1775);
PAINT MONO (-3325 1775);
DISPLAY INVISIBLE (-3325 1775);
FORCEPROP 1 LAST BODY_TYPE PLUMBING
J 0
(-3325 1825);
DISPLAY 0.872340 (-3325 1825);
PAINT GREEN (-3325 1825);
DISPLAY INVISIBLE (-3325 1825);
FORCEPROP 1 LAST HDL_TAP TRUE
J 0
(-3000 1650);
DISPLAY 0.872340 (-3000 1650);
DISPLAY INVISIBLE (-3000 1650);
FORCEPROP 1 LAST PATH I239
J 0
(-3327 1775);
DISPLAY 0.872340 (-3327 1775);
PAINT GREEN (-3327 1775);
DISPLAY INVISIBLE (-3327 1775);
FORCEADD TAP..1
(-3325 1725);
FORCEPROP 3 LASTPIN (-3375 1725) SIG_NAME M_H_CPU0_SB_CB<4>
J 0
(-3365 1735);
DISPLAY 0.659574 (-3365 1735);
PAINT MONO (-3365 1735);
DISPLAY INVISIBLE (-3365 1735);
FORCEPROP 1 LASTPIN (-3375 1725) BN 4
J 0
(-3387 1733);
DISPLAY 0.489362 (-3387 1733);
PAINT GREEN (-3387 1733);
FORCEPROP 2 LAST CDS_LIB mstr_standard
J 2
(-3325 1725);
DISPLAY 0.723404 (-3325 1725);
PAINT MONO (-3325 1725);
DISPLAY INVISIBLE (-3325 1725);
FORCEPROP 1 LAST BODY_TYPE PLUMBING
J 0
(-3325 1775);
DISPLAY 0.872340 (-3325 1775);
PAINT GREEN (-3325 1775);
DISPLAY INVISIBLE (-3325 1775);
FORCEPROP 1 LAST HDL_TAP TRUE
J 0
(-3000 1600);
DISPLAY 0.872340 (-3000 1600);
DISPLAY INVISIBLE (-3000 1600);
FORCEPROP 1 LAST PATH I240
J 0
(-3327 1725);
DISPLAY 0.872340 (-3327 1725);
PAINT GREEN (-3327 1725);
DISPLAY INVISIBLE (-3327 1725);
FORCEADD TAP..1
(-3325 1675);
FORCEPROP 3 LASTPIN (-3375 1675) SIG_NAME M_H_CPU0_SB_CB<5>
J 0
(-3365 1685);
DISPLAY 0.659574 (-3365 1685);
PAINT MONO (-3365 1685);
DISPLAY INVISIBLE (-3365 1685);
FORCEPROP 1 LASTPIN (-3375 1675) BN 5
J 0
(-3387 1683);
DISPLAY 0.489362 (-3387 1683);
PAINT GREEN (-3387 1683);
FORCEPROP 2 LAST CDS_LIB mstr_standard
J 2
(-3325 1675);
DISPLAY 0.723404 (-3325 1675);
PAINT MONO (-3325 1675);
DISPLAY INVISIBLE (-3325 1675);
FORCEPROP 1 LAST BODY_TYPE PLUMBING
J 0
(-3325 1725);
DISPLAY 0.872340 (-3325 1725);
PAINT GREEN (-3325 1725);
DISPLAY INVISIBLE (-3325 1725);
FORCEPROP 1 LAST HDL_TAP TRUE
J 0
(-3000 1550);
DISPLAY 0.872340 (-3000 1550);
DISPLAY INVISIBLE (-3000 1550);
FORCEPROP 1 LAST PATH I241
J 0
(-3327 1675);
DISPLAY 0.872340 (-3327 1675);
PAINT GREEN (-3327 1675);
DISPLAY INVISIBLE (-3327 1675);
FORCEADD TAP..1
(-3325 1575);
FORCEPROP 3 LASTPIN (-3375 1575) SIG_NAME M_H_CPU0_SB_CB<7>
J 0
(-3365 1585);
DISPLAY 0.659574 (-3365 1585);
PAINT MONO (-3365 1585);
DISPLAY INVISIBLE (-3365 1585);
FORCEPROP 1 LASTPIN (-3375 1575) BN 7
J 0
(-3387 1583);
DISPLAY 0.489362 (-3387 1583);
PAINT GREEN (-3387 1583);
FORCEPROP 2 LAST CDS_LIB mstr_standard
J 2
(-3325 1575);
DISPLAY 0.723404 (-3325 1575);
PAINT MONO (-3325 1575);
DISPLAY INVISIBLE (-3325 1575);
FORCEPROP 1 LAST BODY_TYPE PLUMBING
J 0
(-3325 1625);
DISPLAY 0.872340 (-3325 1625);
PAINT GREEN (-3325 1625);
DISPLAY INVISIBLE (-3325 1625);
FORCEPROP 1 LAST HDL_TAP TRUE
J 0
(-3000 1450);
DISPLAY 0.872340 (-3000 1450);
DISPLAY INVISIBLE (-3000 1450);
FORCEPROP 1 LAST PATH I242
J 0
(-3327 1575);
DISPLAY 0.872340 (-3327 1575);
PAINT GREEN (-3327 1575);
DISPLAY INVISIBLE (-3327 1575);
FORCEADD TAP..1
(-3325 1625);
FORCEPROP 3 LASTPIN (-3375 1625) SIG_NAME M_H_CPU0_SB_CB<6>
J 0
(-3365 1635);
DISPLAY 0.659574 (-3365 1635);
PAINT MONO (-3365 1635);
DISPLAY INVISIBLE (-3365 1635);
FORCEPROP 1 LASTPIN (-3375 1625) BN 6
J 0
(-3387 1633);
DISPLAY 0.489362 (-3387 1633);
PAINT GREEN (-3387 1633);
FORCEPROP 2 LAST CDS_LIB mstr_standard
J 2
(-3325 1625);
DISPLAY 0.723404 (-3325 1625);
PAINT MONO (-3325 1625);
DISPLAY INVISIBLE (-3325 1625);
FORCEPROP 1 LAST BODY_TYPE PLUMBING
J 0
(-3325 1675);
DISPLAY 0.872340 (-3325 1675);
PAINT GREEN (-3325 1675);
DISPLAY INVISIBLE (-3325 1675);
FORCEPROP 1 LAST HDL_TAP TRUE
J 0
(-3000 1500);
DISPLAY 0.872340 (-3000 1500);
DISPLAY INVISIBLE (-3000 1500);
FORCEPROP 1 LAST PATH I243
J 0
(-3327 1625);
DISPLAY 0.872340 (-3327 1625);
PAINT GREEN (-3327 1625);
DISPLAY INVISIBLE (-3327 1625);
FORCEADD TAP..1
R 2
(-5750 5975);
FORCEPROP 3 LASTPIN (-5700 5975) SIG_NAME M_H_CPU0_SA_DQS_DP<0>
J 0
(-5690 5985);
DISPLAY 0.659574 (-5690 5985);
PAINT MONO (-5690 5985);
DISPLAY INVISIBLE (-5690 5985);
FORCEPROP 1 LASTPIN (-5700 5975) BN 0
J 2
(-5688 5983);
DISPLAY 0.489362 (-5688 5983);
PAINT GREEN (-5688 5983);
FORCEPROP 2 LAST CDS_LIB mstr_standard
J 2
(-5750 5975);
DISPLAY 0.723404 (-5750 5975);
PAINT MONO (-5750 5975);
DISPLAY INVISIBLE (-5750 5975);
FORCEPROP 1 LAST BODY_TYPE PLUMBING
J 2
(-5750 6025);
DISPLAY 0.872340 (-5750 6025);
PAINT GREEN (-5750 6025);
DISPLAY INVISIBLE (-5750 6025);
FORCEPROP 1 LAST HDL_TAP TRUE
J 2
(-6075 5850);
DISPLAY 0.872340 (-6075 5850);
DISPLAY INVISIBLE (-6075 5850);
FORCEPROP 1 LAST PATH I244
J 2
(-5748 5975);
DISPLAY 0.872340 (-5748 5975);
PAINT GREEN (-5748 5975);
DISPLAY INVISIBLE (-5748 5975);
FORCEADD TAP..1
R 2
(-5750 5775);
FORCEPROP 3 LASTPIN (-5700 5775) SIG_NAME M_H_CPU0_SA_DQS_DP<2>
J 0
(-5690 5785);
DISPLAY 0.659574 (-5690 5785);
PAINT MONO (-5690 5785);
DISPLAY INVISIBLE (-5690 5785);
FORCEPROP 1 LASTPIN (-5700 5775) BN 2
J 2
(-5688 5783);
DISPLAY 0.489362 (-5688 5783);
PAINT GREEN (-5688 5783);
FORCEPROP 2 LAST CDS_LIB mstr_standard
J 2
(-5750 5775);
DISPLAY 0.723404 (-5750 5775);
PAINT MONO (-5750 5775);
DISPLAY INVISIBLE (-5750 5775);
FORCEPROP 1 LAST BODY_TYPE PLUMBING
J 2
(-5750 5825);
DISPLAY 0.872340 (-5750 5825);
PAINT GREEN (-5750 5825);
DISPLAY INVISIBLE (-5750 5825);
FORCEPROP 1 LAST HDL_TAP TRUE
J 2
(-6075 5650);
DISPLAY 0.872340 (-6075 5650);
DISPLAY INVISIBLE (-6075 5650);
FORCEPROP 1 LAST PATH I245
J 2
(-5748 5775);
DISPLAY 0.872340 (-5748 5775);
PAINT GREEN (-5748 5775);
DISPLAY INVISIBLE (-5748 5775);
FORCEADD TAP..1
R 2
(-5750 5875);
FORCEPROP 3 LASTPIN (-5700 5875) SIG_NAME M_H_CPU0_SA_DQS_DP<1>
J 0
(-5690 5885);
DISPLAY 0.659574 (-5690 5885);
PAINT MONO (-5690 5885);
DISPLAY INVISIBLE (-5690 5885);
FORCEPROP 1 LASTPIN (-5700 5875) BN 1
J 2
(-5688 5883);
DISPLAY 0.489362 (-5688 5883);
PAINT GREEN (-5688 5883);
FORCEPROP 2 LAST CDS_LIB mstr_standard
J 2
(-5750 5875);
DISPLAY 0.723404 (-5750 5875);
PAINT MONO (-5750 5875);
DISPLAY INVISIBLE (-5750 5875);
FORCEPROP 1 LAST BODY_TYPE PLUMBING
J 2
(-5750 5925);
DISPLAY 0.872340 (-5750 5925);
PAINT GREEN (-5750 5925);
DISPLAY INVISIBLE (-5750 5925);
FORCEPROP 1 LAST HDL_TAP TRUE
J 2
(-6075 5750);
DISPLAY 0.872340 (-6075 5750);
DISPLAY INVISIBLE (-6075 5750);
FORCEPROP 1 LAST PATH I246
J 2
(-5748 5875);
DISPLAY 0.872340 (-5748 5875);
PAINT GREEN (-5748 5875);
DISPLAY INVISIBLE (-5748 5875);
FORCEADD TAP..1
R 2
(-5750 5675);
FORCEPROP 3 LASTPIN (-5700 5675) SIG_NAME M_H_CPU0_SA_DQS_DP<3>
J 0
(-5690 5685);
DISPLAY 0.659574 (-5690 5685);
PAINT MONO (-5690 5685);
DISPLAY INVISIBLE (-5690 5685);
FORCEPROP 1 LASTPIN (-5700 5675) BN 3
J 2
(-5688 5683);
DISPLAY 0.489362 (-5688 5683);
PAINT GREEN (-5688 5683);
FORCEPROP 2 LAST CDS_LIB mstr_standard
J 2
(-5750 5675);
DISPLAY 0.723404 (-5750 5675);
PAINT MONO (-5750 5675);
DISPLAY INVISIBLE (-5750 5675);
FORCEPROP 1 LAST BODY_TYPE PLUMBING
J 2
(-5750 5725);
DISPLAY 0.872340 (-5750 5725);
PAINT GREEN (-5750 5725);
DISPLAY INVISIBLE (-5750 5725);
FORCEPROP 1 LAST HDL_TAP TRUE
J 2
(-6075 5550);
DISPLAY 0.872340 (-6075 5550);
DISPLAY INVISIBLE (-6075 5550);
FORCEPROP 1 LAST PATH I247
J 2
(-5748 5675);
DISPLAY 0.872340 (-5748 5675);
PAINT GREEN (-5748 5675);
DISPLAY INVISIBLE (-5748 5675);
FORCEADD TAP..1
R 2
(-5950 5925);
FORCEPROP 3 LASTPIN (-5900 5925) SIG_NAME M_H_CPU0_SA_DQS_DN<0>
J 0
(-5890 5935);
DISPLAY 0.659574 (-5890 5935);
PAINT MONO (-5890 5935);
DISPLAY INVISIBLE (-5890 5935);
FORCEPROP 1 LASTPIN (-5900 5925) BN 0
J 2
(-5888 5933);
DISPLAY 0.489362 (-5888 5933);
PAINT GREEN (-5888 5933);
FORCEPROP 2 LAST CDS_LIB mstr_standard
J 2
(-5950 5925);
DISPLAY 0.723404 (-5950 5925);
PAINT MONO (-5950 5925);
DISPLAY INVISIBLE (-5950 5925);
FORCEPROP 1 LAST BODY_TYPE PLUMBING
J 2
(-5950 5975);
DISPLAY 0.872340 (-5950 5975);
PAINT GREEN (-5950 5975);
DISPLAY INVISIBLE (-5950 5975);
FORCEPROP 1 LAST HDL_TAP TRUE
J 2
(-6275 5800);
DISPLAY 0.872340 (-6275 5800);
DISPLAY INVISIBLE (-6275 5800);
FORCEPROP 1 LAST PATH I248
J 2
(-5948 5925);
DISPLAY 0.872340 (-5948 5925);
PAINT GREEN (-5948 5925);
DISPLAY INVISIBLE (-5948 5925);
FORCEADD TAP..1
R 2
(-5950 5825);
FORCEPROP 3 LASTPIN (-5900 5825) SIG_NAME M_H_CPU0_SA_DQS_DN<1>
J 0
(-5890 5835);
DISPLAY 0.659574 (-5890 5835);
PAINT MONO (-5890 5835);
DISPLAY INVISIBLE (-5890 5835);
FORCEPROP 1 LASTPIN (-5900 5825) BN 1
J 2
(-5888 5833);
DISPLAY 0.489362 (-5888 5833);
PAINT GREEN (-5888 5833);
FORCEPROP 2 LAST CDS_LIB mstr_standard
J 2
(-5950 5825);
DISPLAY 0.723404 (-5950 5825);
PAINT MONO (-5950 5825);
DISPLAY INVISIBLE (-5950 5825);
FORCEPROP 1 LAST BODY_TYPE PLUMBING
J 2
(-5950 5875);
DISPLAY 0.872340 (-5950 5875);
PAINT GREEN (-5950 5875);
DISPLAY INVISIBLE (-5950 5875);
FORCEPROP 1 LAST HDL_TAP TRUE
J 2
(-6275 5700);
DISPLAY 0.872340 (-6275 5700);
DISPLAY INVISIBLE (-6275 5700);
FORCEPROP 1 LAST PATH I249
J 2
(-5948 5825);
DISPLAY 0.872340 (-5948 5825);
PAINT GREEN (-5948 5825);
DISPLAY INVISIBLE (-5948 5825);
FORCEADD TAP..1
R 2
(-5950 5725);
FORCEPROP 3 LASTPIN (-5900 5725) SIG_NAME M_H_CPU0_SA_DQS_DN<2>
J 0
(-5890 5735);
DISPLAY 0.659574 (-5890 5735);
PAINT MONO (-5890 5735);
DISPLAY INVISIBLE (-5890 5735);
FORCEPROP 1 LASTPIN (-5900 5725) BN 2
J 2
(-5888 5733);
DISPLAY 0.489362 (-5888 5733);
PAINT GREEN (-5888 5733);
FORCEPROP 2 LAST CDS_LIB mstr_standard
J 2
(-5950 5725);
DISPLAY 0.723404 (-5950 5725);
PAINT MONO (-5950 5725);
DISPLAY INVISIBLE (-5950 5725);
FORCEPROP 1 LAST BODY_TYPE PLUMBING
J 2
(-5950 5775);
DISPLAY 0.872340 (-5950 5775);
PAINT GREEN (-5950 5775);
DISPLAY INVISIBLE (-5950 5775);
FORCEPROP 1 LAST HDL_TAP TRUE
J 2
(-6275 5600);
DISPLAY 0.872340 (-6275 5600);
DISPLAY INVISIBLE (-6275 5600);
FORCEPROP 1 LAST PATH I250
J 2
(-5948 5725);
DISPLAY 0.872340 (-5948 5725);
PAINT GREEN (-5948 5725);
DISPLAY INVISIBLE (-5948 5725);
FORCEADD TAP..1
R 2
(-5750 5575);
FORCEPROP 3 LASTPIN (-5700 5575) SIG_NAME M_H_CPU0_SA_DQS_DP<4>
J 0
(-5690 5585);
DISPLAY 0.659574 (-5690 5585);
PAINT MONO (-5690 5585);
DISPLAY INVISIBLE (-5690 5585);
FORCEPROP 1 LASTPIN (-5700 5575) BN 4
J 2
(-5688 5583);
DISPLAY 0.489362 (-5688 5583);
PAINT GREEN (-5688 5583);
FORCEPROP 2 LAST CDS_LIB mstr_standard
J 2
(-5750 5575);
DISPLAY 0.723404 (-5750 5575);
PAINT MONO (-5750 5575);
DISPLAY INVISIBLE (-5750 5575);
FORCEPROP 1 LAST BODY_TYPE PLUMBING
J 2
(-5750 5625);
DISPLAY 0.872340 (-5750 5625);
PAINT GREEN (-5750 5625);
DISPLAY INVISIBLE (-5750 5625);
FORCEPROP 1 LAST HDL_TAP TRUE
J 2
(-6075 5450);
DISPLAY 0.872340 (-6075 5450);
DISPLAY INVISIBLE (-6075 5450);
FORCEPROP 1 LAST PATH I251
J 2
(-5748 5575);
DISPLAY 0.872340 (-5748 5575);
PAINT GREEN (-5748 5575);
DISPLAY INVISIBLE (-5748 5575);
FORCEADD TAP..1
R 2
(-5750 5475);
FORCEPROP 3 LASTPIN (-5700 5475) SIG_NAME M_H_CPU0_SA_DQS_DP<5>
J 0
(-5690 5485);
DISPLAY 0.659574 (-5690 5485);
PAINT MONO (-5690 5485);
DISPLAY INVISIBLE (-5690 5485);
FORCEPROP 1 LASTPIN (-5700 5475) BN 5
J 2
(-5688 5483);
DISPLAY 0.489362 (-5688 5483);
PAINT GREEN (-5688 5483);
FORCEPROP 2 LAST CDS_LIB mstr_standard
J 2
(-5750 5475);
DISPLAY 0.723404 (-5750 5475);
PAINT MONO (-5750 5475);
DISPLAY INVISIBLE (-5750 5475);
FORCEPROP 1 LAST BODY_TYPE PLUMBING
J 2
(-5750 5525);
DISPLAY 0.872340 (-5750 5525);
PAINT GREEN (-5750 5525);
DISPLAY INVISIBLE (-5750 5525);
FORCEPROP 1 LAST HDL_TAP TRUE
J 2
(-6075 5350);
DISPLAY 0.872340 (-6075 5350);
DISPLAY INVISIBLE (-6075 5350);
FORCEPROP 1 LAST PATH I252
J 2
(-5748 5475);
DISPLAY 0.872340 (-5748 5475);
PAINT GREEN (-5748 5475);
DISPLAY INVISIBLE (-5748 5475);
FORCEADD TAP..1
R 2
(-5950 5625);
FORCEPROP 3 LASTPIN (-5900 5625) SIG_NAME M_H_CPU0_SA_DQS_DN<3>
J 0
(-5890 5635);
DISPLAY 0.659574 (-5890 5635);
PAINT MONO (-5890 5635);
DISPLAY INVISIBLE (-5890 5635);
FORCEPROP 1 LASTPIN (-5900 5625) BN 3
J 2
(-5888 5633);
DISPLAY 0.489362 (-5888 5633);
PAINT GREEN (-5888 5633);
FORCEPROP 2 LAST CDS_LIB mstr_standard
J 2
(-5950 5625);
DISPLAY 0.723404 (-5950 5625);
PAINT MONO (-5950 5625);
DISPLAY INVISIBLE (-5950 5625);
FORCEPROP 1 LAST BODY_TYPE PLUMBING
J 2
(-5950 5675);
DISPLAY 0.872340 (-5950 5675);
PAINT GREEN (-5950 5675);
DISPLAY INVISIBLE (-5950 5675);
FORCEPROP 1 LAST HDL_TAP TRUE
J 2
(-6275 5500);
DISPLAY 0.872340 (-6275 5500);
DISPLAY INVISIBLE (-6275 5500);
FORCEPROP 1 LAST PATH I253
J 2
(-5948 5625);
DISPLAY 0.872340 (-5948 5625);
PAINT GREEN (-5948 5625);
DISPLAY INVISIBLE (-5948 5625);
FORCEADD TAP..1
R 2
(-5750 5375);
FORCEPROP 3 LASTPIN (-5700 5375) SIG_NAME M_H_CPU0_SA_DQS_DP<6>
J 0
(-5690 5385);
DISPLAY 0.659574 (-5690 5385);
PAINT MONO (-5690 5385);
DISPLAY INVISIBLE (-5690 5385);
FORCEPROP 1 LASTPIN (-5700 5375) BN 6
J 2
(-5688 5383);
DISPLAY 0.489362 (-5688 5383);
PAINT GREEN (-5688 5383);
FORCEPROP 2 LAST CDS_LIB mstr_standard
J 2
(-5750 5375);
DISPLAY 0.723404 (-5750 5375);
PAINT MONO (-5750 5375);
DISPLAY INVISIBLE (-5750 5375);
FORCEPROP 1 LAST BODY_TYPE PLUMBING
J 2
(-5750 5425);
DISPLAY 0.872340 (-5750 5425);
PAINT GREEN (-5750 5425);
DISPLAY INVISIBLE (-5750 5425);
FORCEPROP 1 LAST HDL_TAP TRUE
J 2
(-6075 5250);
DISPLAY 0.872340 (-6075 5250);
DISPLAY INVISIBLE (-6075 5250);
FORCEPROP 1 LAST PATH I254
J 2
(-5748 5375);
DISPLAY 0.872340 (-5748 5375);
PAINT GREEN (-5748 5375);
DISPLAY INVISIBLE (-5748 5375);
FORCEADD TAP..1
R 2
(-5750 5275);
FORCEPROP 3 LASTPIN (-5700 5275) SIG_NAME M_H_CPU0_SA_DQS_DP<7>
J 0
(-5690 5285);
DISPLAY 0.659574 (-5690 5285);
PAINT MONO (-5690 5285);
DISPLAY INVISIBLE (-5690 5285);
FORCEPROP 1 LASTPIN (-5700 5275) BN 7
J 2
(-5688 5283);
DISPLAY 0.489362 (-5688 5283);
PAINT GREEN (-5688 5283);
FORCEPROP 2 LAST CDS_LIB mstr_standard
J 2
(-5750 5275);
DISPLAY 0.723404 (-5750 5275);
PAINT MONO (-5750 5275);
DISPLAY INVISIBLE (-5750 5275);
FORCEPROP 1 LAST BODY_TYPE PLUMBING
J 2
(-5750 5325);
DISPLAY 0.872340 (-5750 5325);
PAINT GREEN (-5750 5325);
DISPLAY INVISIBLE (-5750 5325);
FORCEPROP 1 LAST HDL_TAP TRUE
J 2
(-6075 5150);
DISPLAY 0.872340 (-6075 5150);
DISPLAY INVISIBLE (-6075 5150);
FORCEPROP 1 LAST PATH I255
J 2
(-5748 5275);
DISPLAY 0.872340 (-5748 5275);
PAINT GREEN (-5748 5275);
DISPLAY INVISIBLE (-5748 5275);
FORCEADD TAP..1
R 2
(-5750 5175);
FORCEPROP 3 LASTPIN (-5700 5175) SIG_NAME M_H_CPU0_SA_DQS_DP<8>
J 0
(-5690 5185);
DISPLAY 0.659574 (-5690 5185);
PAINT MONO (-5690 5185);
DISPLAY INVISIBLE (-5690 5185);
FORCEPROP 1 LASTPIN (-5700 5175) BN 8
J 2
(-5688 5183);
DISPLAY 0.489362 (-5688 5183);
PAINT GREEN (-5688 5183);
FORCEPROP 2 LAST CDS_LIB mstr_standard
J 2
(-5750 5175);
DISPLAY 0.723404 (-5750 5175);
PAINT MONO (-5750 5175);
DISPLAY INVISIBLE (-5750 5175);
FORCEPROP 1 LAST BODY_TYPE PLUMBING
J 2
(-5750 5225);
DISPLAY 0.872340 (-5750 5225);
PAINT GREEN (-5750 5225);
DISPLAY INVISIBLE (-5750 5225);
FORCEPROP 1 LAST HDL_TAP TRUE
J 2
(-6075 5050);
DISPLAY 0.872340 (-6075 5050);
DISPLAY INVISIBLE (-6075 5050);
FORCEPROP 1 LAST PATH I256
J 2
(-5748 5175);
DISPLAY 0.872340 (-5748 5175);
PAINT GREEN (-5748 5175);
DISPLAY INVISIBLE (-5748 5175);
FORCEADD TAP..1
R 2
(-5950 5525);
FORCEPROP 3 LASTPIN (-5900 5525) SIG_NAME M_H_CPU0_SA_DQS_DN<4>
J 0
(-5890 5535);
DISPLAY 0.659574 (-5890 5535);
PAINT MONO (-5890 5535);
DISPLAY INVISIBLE (-5890 5535);
FORCEPROP 1 LASTPIN (-5900 5525) BN 4
J 2
(-5888 5533);
DISPLAY 0.489362 (-5888 5533);
PAINT GREEN (-5888 5533);
FORCEPROP 2 LAST CDS_LIB mstr_standard
J 2
(-5950 5525);
DISPLAY 0.723404 (-5950 5525);
PAINT MONO (-5950 5525);
DISPLAY INVISIBLE (-5950 5525);
FORCEPROP 1 LAST BODY_TYPE PLUMBING
J 2
(-5950 5575);
DISPLAY 0.872340 (-5950 5575);
PAINT GREEN (-5950 5575);
DISPLAY INVISIBLE (-5950 5575);
FORCEPROP 1 LAST HDL_TAP TRUE
J 2
(-6275 5400);
DISPLAY 0.872340 (-6275 5400);
DISPLAY INVISIBLE (-6275 5400);
FORCEPROP 1 LAST PATH I257
J 2
(-5948 5525);
DISPLAY 0.872340 (-5948 5525);
PAINT GREEN (-5948 5525);
DISPLAY INVISIBLE (-5948 5525);
FORCEADD TAP..1
R 2
(-5950 5425);
FORCEPROP 3 LASTPIN (-5900 5425) SIG_NAME M_H_CPU0_SA_DQS_DN<5>
J 0
(-5890 5435);
DISPLAY 0.659574 (-5890 5435);
PAINT MONO (-5890 5435);
DISPLAY INVISIBLE (-5890 5435);
FORCEPROP 1 LASTPIN (-5900 5425) BN 5
J 2
(-5888 5433);
DISPLAY 0.489362 (-5888 5433);
PAINT GREEN (-5888 5433);
FORCEPROP 2 LAST CDS_LIB mstr_standard
J 2
(-5950 5425);
DISPLAY 0.723404 (-5950 5425);
PAINT MONO (-5950 5425);
DISPLAY INVISIBLE (-5950 5425);
FORCEPROP 1 LAST BODY_TYPE PLUMBING
J 2
(-5950 5475);
DISPLAY 0.872340 (-5950 5475);
PAINT GREEN (-5950 5475);
DISPLAY INVISIBLE (-5950 5475);
FORCEPROP 1 LAST HDL_TAP TRUE
J 2
(-6275 5300);
DISPLAY 0.872340 (-6275 5300);
DISPLAY INVISIBLE (-6275 5300);
FORCEPROP 1 LAST PATH I258
J 2
(-5948 5425);
DISPLAY 0.872340 (-5948 5425);
PAINT GREEN (-5948 5425);
DISPLAY INVISIBLE (-5948 5425);
FORCEADD TAP..1
R 2
(-5950 5325);
FORCEPROP 3 LASTPIN (-5900 5325) SIG_NAME M_H_CPU0_SA_DQS_DN<6>
J 0
(-5890 5335);
DISPLAY 0.659574 (-5890 5335);
PAINT MONO (-5890 5335);
DISPLAY INVISIBLE (-5890 5335);
FORCEPROP 1 LASTPIN (-5900 5325) BN 6
J 2
(-5888 5333);
DISPLAY 0.489362 (-5888 5333);
PAINT GREEN (-5888 5333);
FORCEPROP 2 LAST CDS_LIB mstr_standard
J 2
(-5950 5325);
DISPLAY 0.723404 (-5950 5325);
PAINT MONO (-5950 5325);
DISPLAY INVISIBLE (-5950 5325);
FORCEPROP 1 LAST BODY_TYPE PLUMBING
J 2
(-5950 5375);
DISPLAY 0.872340 (-5950 5375);
PAINT GREEN (-5950 5375);
DISPLAY INVISIBLE (-5950 5375);
FORCEPROP 1 LAST HDL_TAP TRUE
J 2
(-6275 5200);
DISPLAY 0.872340 (-6275 5200);
DISPLAY INVISIBLE (-6275 5200);
FORCEPROP 1 LAST PATH I259
J 2
(-5948 5325);
DISPLAY 0.872340 (-5948 5325);
PAINT GREEN (-5948 5325);
DISPLAY INVISIBLE (-5948 5325);
FORCEADD TAP..1
R 2
(-5950 5125);
FORCEPROP 3 LASTPIN (-5900 5125) SIG_NAME M_H_CPU0_SA_DQS_DN<8>
J 0
(-5890 5135);
DISPLAY 0.659574 (-5890 5135);
PAINT MONO (-5890 5135);
DISPLAY INVISIBLE (-5890 5135);
FORCEPROP 1 LASTPIN (-5900 5125) BN 8
J 2
(-5888 5133);
DISPLAY 0.489362 (-5888 5133);
PAINT GREEN (-5888 5133);
FORCEPROP 2 LAST CDS_LIB mstr_standard
J 2
(-5950 5125);
DISPLAY 0.723404 (-5950 5125);
PAINT MONO (-5950 5125);
DISPLAY INVISIBLE (-5950 5125);
FORCEPROP 1 LAST BODY_TYPE PLUMBING
J 2
(-5950 5175);
DISPLAY 0.872340 (-5950 5175);
PAINT GREEN (-5950 5175);
DISPLAY INVISIBLE (-5950 5175);
FORCEPROP 1 LAST HDL_TAP TRUE
J 2
(-6275 5000);
DISPLAY 0.872340 (-6275 5000);
DISPLAY INVISIBLE (-6275 5000);
FORCEPROP 1 LAST PATH I260
J 2
(-5948 5125);
DISPLAY 0.872340 (-5948 5125);
PAINT GREEN (-5948 5125);
DISPLAY INVISIBLE (-5948 5125);
FORCEADD TAP..1
R 2
(-5950 5225);
FORCEPROP 3 LASTPIN (-5900 5225) SIG_NAME M_H_CPU0_SA_DQS_DN<7>
J 0
(-5890 5235);
DISPLAY 0.659574 (-5890 5235);
PAINT MONO (-5890 5235);
DISPLAY INVISIBLE (-5890 5235);
FORCEPROP 1 LASTPIN (-5900 5225) BN 7
J 2
(-5888 5233);
DISPLAY 0.489362 (-5888 5233);
PAINT GREEN (-5888 5233);
FORCEPROP 2 LAST CDS_LIB mstr_standard
J 2
(-5950 5225);
DISPLAY 0.723404 (-5950 5225);
PAINT MONO (-5950 5225);
DISPLAY INVISIBLE (-5950 5225);
FORCEPROP 1 LAST BODY_TYPE PLUMBING
J 2
(-5950 5275);
DISPLAY 0.872340 (-5950 5275);
PAINT GREEN (-5950 5275);
DISPLAY INVISIBLE (-5950 5275);
FORCEPROP 1 LAST HDL_TAP TRUE
J 2
(-6275 5100);
DISPLAY 0.872340 (-6275 5100);
DISPLAY INVISIBLE (-6275 5100);
FORCEPROP 1 LAST PATH I261
J 2
(-5948 5225);
DISPLAY 0.872340 (-5948 5225);
PAINT GREEN (-5948 5225);
DISPLAY INVISIBLE (-5948 5225);
FORCEADD TAP..1
R 2
(-5750 5075);
FORCEPROP 3 LASTPIN (-5700 5075) SIG_NAME M_H_CPU0_SA_DQS_DP<9>
J 0
(-5690 5085);
DISPLAY 0.659574 (-5690 5085);
PAINT MONO (-5690 5085);
DISPLAY INVISIBLE (-5690 5085);
FORCEPROP 1 LASTPIN (-5700 5075) BN 9
J 2
(-5688 5083);
DISPLAY 0.489362 (-5688 5083);
PAINT GREEN (-5688 5083);
FORCEPROP 2 LAST CDS_LIB mstr_standard
J 2
(-5750 5075);
DISPLAY 0.723404 (-5750 5075);
PAINT MONO (-5750 5075);
DISPLAY INVISIBLE (-5750 5075);
FORCEPROP 1 LAST BODY_TYPE PLUMBING
J 2
(-5750 5125);
DISPLAY 0.872340 (-5750 5125);
PAINT GREEN (-5750 5125);
DISPLAY INVISIBLE (-5750 5125);
FORCEPROP 1 LAST HDL_TAP TRUE
J 2
(-6075 4950);
DISPLAY 0.872340 (-6075 4950);
DISPLAY INVISIBLE (-6075 4950);
FORCEPROP 1 LAST PATH I262
J 2
(-5748 5075);
DISPLAY 0.872340 (-5748 5075);
PAINT GREEN (-5748 5075);
DISPLAY INVISIBLE (-5748 5075);
FORCEADD TAP..1
R 2
(-5750 4925);
FORCEPROP 3 LASTPIN (-5700 4925) SIG_NAME M_H_CPU0_SB_DQS_DP<0>
J 0
(-5690 4935);
DISPLAY 0.659574 (-5690 4935);
PAINT MONO (-5690 4935);
DISPLAY INVISIBLE (-5690 4935);
FORCEPROP 1 LASTPIN (-5700 4925) BN 0
J 2
(-5688 4933);
DISPLAY 0.489362 (-5688 4933);
PAINT GREEN (-5688 4933);
FORCEPROP 2 LAST CDS_LIB mstr_standard
J 2
(-5750 4925);
DISPLAY 0.723404 (-5750 4925);
PAINT MONO (-5750 4925);
DISPLAY INVISIBLE (-5750 4925);
FORCEPROP 1 LAST BODY_TYPE PLUMBING
J 2
(-5750 4975);
DISPLAY 0.872340 (-5750 4975);
PAINT GREEN (-5750 4975);
DISPLAY INVISIBLE (-5750 4975);
FORCEPROP 1 LAST HDL_TAP TRUE
J 2
(-6075 4800);
DISPLAY 0.872340 (-6075 4800);
DISPLAY INVISIBLE (-6075 4800);
FORCEPROP 1 LAST PATH I263
J 2
(-5748 4925);
DISPLAY 0.872340 (-5748 4925);
PAINT GREEN (-5748 4925);
DISPLAY INVISIBLE (-5748 4925);
FORCEADD TAP..1
R 2
(-5750 4825);
FORCEPROP 3 LASTPIN (-5700 4825) SIG_NAME M_H_CPU0_SB_DQS_DP<1>
J 0
(-5690 4835);
DISPLAY 0.659574 (-5690 4835);
PAINT MONO (-5690 4835);
DISPLAY INVISIBLE (-5690 4835);
FORCEPROP 1 LASTPIN (-5700 4825) BN 1
J 2
(-5688 4833);
DISPLAY 0.489362 (-5688 4833);
PAINT GREEN (-5688 4833);
FORCEPROP 2 LAST CDS_LIB mstr_standard
J 2
(-5750 4825);
DISPLAY 0.723404 (-5750 4825);
PAINT MONO (-5750 4825);
DISPLAY INVISIBLE (-5750 4825);
FORCEPROP 1 LAST BODY_TYPE PLUMBING
J 2
(-5750 4875);
DISPLAY 0.872340 (-5750 4875);
PAINT GREEN (-5750 4875);
DISPLAY INVISIBLE (-5750 4875);
FORCEPROP 1 LAST HDL_TAP TRUE
J 2
(-6075 4700);
DISPLAY 0.872340 (-6075 4700);
DISPLAY INVISIBLE (-6075 4700);
FORCEPROP 1 LAST PATH I264
J 2
(-5748 4825);
DISPLAY 0.872340 (-5748 4825);
PAINT GREEN (-5748 4825);
DISPLAY INVISIBLE (-5748 4825);
FORCEADD TAP..1
R 2
(-5750 4725);
FORCEPROP 3 LASTPIN (-5700 4725) SIG_NAME M_H_CPU0_SB_DQS_DP<2>
J 0
(-5690 4735);
DISPLAY 0.659574 (-5690 4735);
PAINT MONO (-5690 4735);
DISPLAY INVISIBLE (-5690 4735);
FORCEPROP 1 LASTPIN (-5700 4725) BN 2
J 2
(-5688 4733);
DISPLAY 0.489362 (-5688 4733);
PAINT GREEN (-5688 4733);
FORCEPROP 2 LAST CDS_LIB mstr_standard
J 2
(-5750 4725);
DISPLAY 0.723404 (-5750 4725);
PAINT MONO (-5750 4725);
DISPLAY INVISIBLE (-5750 4725);
FORCEPROP 1 LAST BODY_TYPE PLUMBING
J 2
(-5750 4775);
DISPLAY 0.872340 (-5750 4775);
PAINT GREEN (-5750 4775);
DISPLAY INVISIBLE (-5750 4775);
FORCEPROP 1 LAST HDL_TAP TRUE
J 2
(-6075 4600);
DISPLAY 0.872340 (-6075 4600);
DISPLAY INVISIBLE (-6075 4600);
FORCEPROP 1 LAST PATH I265
J 2
(-5748 4725);
DISPLAY 0.872340 (-5748 4725);
PAINT GREEN (-5748 4725);
DISPLAY INVISIBLE (-5748 4725);
FORCEADD TAP..1
R 2
(-5750 4625);
FORCEPROP 3 LASTPIN (-5700 4625) SIG_NAME M_H_CPU0_SB_DQS_DP<3>
J 0
(-5690 4635);
DISPLAY 0.659574 (-5690 4635);
PAINT MONO (-5690 4635);
DISPLAY INVISIBLE (-5690 4635);
FORCEPROP 1 LASTPIN (-5700 4625) BN 3
J 2
(-5688 4633);
DISPLAY 0.489362 (-5688 4633);
PAINT GREEN (-5688 4633);
FORCEPROP 2 LAST CDS_LIB mstr_standard
J 2
(-5750 4625);
DISPLAY 0.723404 (-5750 4625);
PAINT MONO (-5750 4625);
DISPLAY INVISIBLE (-5750 4625);
FORCEPROP 1 LAST BODY_TYPE PLUMBING
J 2
(-5750 4675);
DISPLAY 0.872340 (-5750 4675);
PAINT GREEN (-5750 4675);
DISPLAY INVISIBLE (-5750 4675);
FORCEPROP 1 LAST HDL_TAP TRUE
J 2
(-6075 4500);
DISPLAY 0.872340 (-6075 4500);
DISPLAY INVISIBLE (-6075 4500);
FORCEPROP 1 LAST PATH I266
J 2
(-5748 4625);
DISPLAY 0.872340 (-5748 4625);
PAINT GREEN (-5748 4625);
DISPLAY INVISIBLE (-5748 4625);
FORCEADD TAP..1
R 2
(-5950 5025);
FORCEPROP 3 LASTPIN (-5900 5025) SIG_NAME M_H_CPU0_SA_DQS_DN<9>
J 0
(-5890 5035);
DISPLAY 0.659574 (-5890 5035);
PAINT MONO (-5890 5035);
DISPLAY INVISIBLE (-5890 5035);
FORCEPROP 1 LASTPIN (-5900 5025) BN 9
J 2
(-5888 5033);
DISPLAY 0.489362 (-5888 5033);
PAINT GREEN (-5888 5033);
FORCEPROP 2 LAST CDS_LIB mstr_standard
J 2
(-5950 5025);
DISPLAY 0.723404 (-5950 5025);
PAINT MONO (-5950 5025);
DISPLAY INVISIBLE (-5950 5025);
FORCEPROP 1 LAST BODY_TYPE PLUMBING
J 2
(-5950 5075);
DISPLAY 0.872340 (-5950 5075);
PAINT GREEN (-5950 5075);
DISPLAY INVISIBLE (-5950 5075);
FORCEPROP 1 LAST HDL_TAP TRUE
J 2
(-6275 4900);
DISPLAY 0.872340 (-6275 4900);
DISPLAY INVISIBLE (-6275 4900);
FORCEPROP 1 LAST PATH I267
J 2
(-5948 5025);
DISPLAY 0.872340 (-5948 5025);
PAINT GREEN (-5948 5025);
DISPLAY INVISIBLE (-5948 5025);
FORCEADD TAP..1
R 2
(-5950 4875);
FORCEPROP 3 LASTPIN (-5900 4875) SIG_NAME M_H_CPU0_SB_DQS_DN<0>
J 0
(-5890 4885);
DISPLAY 0.659574 (-5890 4885);
PAINT MONO (-5890 4885);
DISPLAY INVISIBLE (-5890 4885);
FORCEPROP 1 LASTPIN (-5900 4875) BN 0
J 2
(-5888 4883);
DISPLAY 0.489362 (-5888 4883);
PAINT GREEN (-5888 4883);
FORCEPROP 2 LAST CDS_LIB mstr_standard
J 2
(-5950 4875);
DISPLAY 0.723404 (-5950 4875);
PAINT MONO (-5950 4875);
DISPLAY INVISIBLE (-5950 4875);
FORCEPROP 1 LAST BODY_TYPE PLUMBING
J 2
(-5950 4925);
DISPLAY 0.872340 (-5950 4925);
PAINT GREEN (-5950 4925);
DISPLAY INVISIBLE (-5950 4925);
FORCEPROP 1 LAST HDL_TAP TRUE
J 2
(-6275 4750);
DISPLAY 0.872340 (-6275 4750);
DISPLAY INVISIBLE (-6275 4750);
FORCEPROP 1 LAST PATH I268
J 2
(-5948 4875);
DISPLAY 0.872340 (-5948 4875);
PAINT GREEN (-5948 4875);
DISPLAY INVISIBLE (-5948 4875);
FORCEADD TAP..1
R 2
(-5950 4775);
FORCEPROP 3 LASTPIN (-5900 4775) SIG_NAME M_H_CPU0_SB_DQS_DN<1>
J 0
(-5890 4785);
DISPLAY 0.659574 (-5890 4785);
PAINT MONO (-5890 4785);
DISPLAY INVISIBLE (-5890 4785);
FORCEPROP 1 LASTPIN (-5900 4775) BN 1
J 2
(-5888 4783);
DISPLAY 0.489362 (-5888 4783);
PAINT GREEN (-5888 4783);
FORCEPROP 2 LAST CDS_LIB mstr_standard
J 2
(-5950 4775);
DISPLAY 0.723404 (-5950 4775);
PAINT MONO (-5950 4775);
DISPLAY INVISIBLE (-5950 4775);
FORCEPROP 1 LAST BODY_TYPE PLUMBING
J 2
(-5950 4825);
DISPLAY 0.872340 (-5950 4825);
PAINT GREEN (-5950 4825);
DISPLAY INVISIBLE (-5950 4825);
FORCEPROP 1 LAST HDL_TAP TRUE
J 2
(-6275 4650);
DISPLAY 0.872340 (-6275 4650);
DISPLAY INVISIBLE (-6275 4650);
FORCEPROP 1 LAST PATH I269
J 2
(-5948 4775);
DISPLAY 0.872340 (-5948 4775);
PAINT GREEN (-5948 4775);
DISPLAY INVISIBLE (-5948 4775);
FORCEADD TAP..1
R 2
(-5950 4675);
FORCEPROP 3 LASTPIN (-5900 4675) SIG_NAME M_H_CPU0_SB_DQS_DN<2>
J 0
(-5890 4685);
DISPLAY 0.659574 (-5890 4685);
PAINT MONO (-5890 4685);
DISPLAY INVISIBLE (-5890 4685);
FORCEPROP 1 LASTPIN (-5900 4675) BN 2
J 2
(-5888 4683);
DISPLAY 0.489362 (-5888 4683);
PAINT GREEN (-5888 4683);
FORCEPROP 2 LAST CDS_LIB mstr_standard
J 2
(-5950 4675);
DISPLAY 0.723404 (-5950 4675);
PAINT MONO (-5950 4675);
DISPLAY INVISIBLE (-5950 4675);
FORCEPROP 1 LAST BODY_TYPE PLUMBING
J 2
(-5950 4725);
DISPLAY 0.872340 (-5950 4725);
PAINT GREEN (-5950 4725);
DISPLAY INVISIBLE (-5950 4725);
FORCEPROP 1 LAST HDL_TAP TRUE
J 2
(-6275 4550);
DISPLAY 0.872340 (-6275 4550);
DISPLAY INVISIBLE (-6275 4550);
FORCEPROP 1 LAST PATH I270
J 2
(-5948 4675);
DISPLAY 0.872340 (-5948 4675);
PAINT GREEN (-5948 4675);
DISPLAY INVISIBLE (-5948 4675);
FORCEADD TAP..1
R 2
(-5750 4525);
FORCEPROP 3 LASTPIN (-5700 4525) SIG_NAME M_H_CPU0_SB_DQS_DP<4>
J 0
(-5690 4535);
DISPLAY 0.659574 (-5690 4535);
PAINT MONO (-5690 4535);
DISPLAY INVISIBLE (-5690 4535);
FORCEPROP 1 LASTPIN (-5700 4525) BN 4
J 2
(-5688 4533);
DISPLAY 0.489362 (-5688 4533);
PAINT GREEN (-5688 4533);
FORCEPROP 2 LAST CDS_LIB mstr_standard
J 2
(-5750 4525);
DISPLAY 0.723404 (-5750 4525);
PAINT MONO (-5750 4525);
DISPLAY INVISIBLE (-5750 4525);
FORCEPROP 1 LAST BODY_TYPE PLUMBING
J 2
(-5750 4575);
DISPLAY 0.872340 (-5750 4575);
PAINT GREEN (-5750 4575);
DISPLAY INVISIBLE (-5750 4575);
FORCEPROP 1 LAST HDL_TAP TRUE
J 2
(-6075 4400);
DISPLAY 0.872340 (-6075 4400);
DISPLAY INVISIBLE (-6075 4400);
FORCEPROP 1 LAST PATH I271
J 2
(-5748 4525);
DISPLAY 0.872340 (-5748 4525);
PAINT GREEN (-5748 4525);
DISPLAY INVISIBLE (-5748 4525);
FORCEADD TAP..1
R 2
(-5750 4425);
FORCEPROP 3 LASTPIN (-5700 4425) SIG_NAME M_H_CPU0_SB_DQS_DP<5>
J 0
(-5690 4435);
DISPLAY 0.659574 (-5690 4435);
PAINT MONO (-5690 4435);
DISPLAY INVISIBLE (-5690 4435);
FORCEPROP 1 LASTPIN (-5700 4425) BN 5
J 2
(-5688 4433);
DISPLAY 0.489362 (-5688 4433);
PAINT GREEN (-5688 4433);
FORCEPROP 2 LAST CDS_LIB mstr_standard
J 2
(-5750 4425);
DISPLAY 0.723404 (-5750 4425);
PAINT MONO (-5750 4425);
DISPLAY INVISIBLE (-5750 4425);
FORCEPROP 1 LAST BODY_TYPE PLUMBING
J 2
(-5750 4475);
DISPLAY 0.872340 (-5750 4475);
PAINT GREEN (-5750 4475);
DISPLAY INVISIBLE (-5750 4475);
FORCEPROP 1 LAST HDL_TAP TRUE
J 2
(-6075 4300);
DISPLAY 0.872340 (-6075 4300);
DISPLAY INVISIBLE (-6075 4300);
FORCEPROP 1 LAST PATH I272
J 2
(-5748 4425);
DISPLAY 0.872340 (-5748 4425);
PAINT GREEN (-5748 4425);
DISPLAY INVISIBLE (-5748 4425);
FORCEADD TAP..1
R 2
(-5750 4325);
FORCEPROP 3 LASTPIN (-5700 4325) SIG_NAME M_H_CPU0_SB_DQS_DP<6>
J 0
(-5690 4335);
DISPLAY 0.659574 (-5690 4335);
PAINT MONO (-5690 4335);
DISPLAY INVISIBLE (-5690 4335);
FORCEPROP 1 LASTPIN (-5700 4325) BN 6
J 2
(-5688 4333);
DISPLAY 0.489362 (-5688 4333);
PAINT GREEN (-5688 4333);
FORCEPROP 2 LAST CDS_LIB mstr_standard
J 2
(-5750 4325);
DISPLAY 0.723404 (-5750 4325);
PAINT MONO (-5750 4325);
DISPLAY INVISIBLE (-5750 4325);
FORCEPROP 1 LAST BODY_TYPE PLUMBING
J 2
(-5750 4375);
DISPLAY 0.872340 (-5750 4375);
PAINT GREEN (-5750 4375);
DISPLAY INVISIBLE (-5750 4375);
FORCEPROP 1 LAST HDL_TAP TRUE
J 2
(-6075 4200);
DISPLAY 0.872340 (-6075 4200);
DISPLAY INVISIBLE (-6075 4200);
FORCEPROP 1 LAST PATH I273
J 2
(-5748 4325);
DISPLAY 0.872340 (-5748 4325);
PAINT GREEN (-5748 4325);
DISPLAY INVISIBLE (-5748 4325);
FORCEADD TAP..1
R 2
(-5750 4225);
FORCEPROP 3 LASTPIN (-5700 4225) SIG_NAME M_H_CPU0_SB_DQS_DP<7>
J 0
(-5690 4235);
DISPLAY 0.659574 (-5690 4235);
PAINT MONO (-5690 4235);
DISPLAY INVISIBLE (-5690 4235);
FORCEPROP 1 LASTPIN (-5700 4225) BN 7
J 2
(-5688 4233);
DISPLAY 0.489362 (-5688 4233);
PAINT GREEN (-5688 4233);
FORCEPROP 2 LAST CDS_LIB mstr_standard
J 2
(-5750 4225);
DISPLAY 0.723404 (-5750 4225);
PAINT MONO (-5750 4225);
DISPLAY INVISIBLE (-5750 4225);
FORCEPROP 1 LAST BODY_TYPE PLUMBING
J 2
(-5750 4275);
DISPLAY 0.872340 (-5750 4275);
PAINT GREEN (-5750 4275);
DISPLAY INVISIBLE (-5750 4275);
FORCEPROP 1 LAST HDL_TAP TRUE
J 2
(-6075 4100);
DISPLAY 0.872340 (-6075 4100);
DISPLAY INVISIBLE (-6075 4100);
FORCEPROP 1 LAST PATH I274
J 2
(-5748 4225);
DISPLAY 0.872340 (-5748 4225);
PAINT GREEN (-5748 4225);
DISPLAY INVISIBLE (-5748 4225);
FORCEADD TAP..1
R 2
(-5750 4125);
FORCEPROP 3 LASTPIN (-5700 4125) SIG_NAME M_H_CPU0_SB_DQS_DP<8>
J 0
(-5690 4135);
DISPLAY 0.659574 (-5690 4135);
PAINT MONO (-5690 4135);
DISPLAY INVISIBLE (-5690 4135);
FORCEPROP 1 LASTPIN (-5700 4125) BN 8
J 2
(-5688 4133);
DISPLAY 0.489362 (-5688 4133);
PAINT GREEN (-5688 4133);
FORCEPROP 2 LAST CDS_LIB mstr_standard
J 2
(-5750 4125);
DISPLAY 0.723404 (-5750 4125);
PAINT MONO (-5750 4125);
DISPLAY INVISIBLE (-5750 4125);
FORCEPROP 1 LAST BODY_TYPE PLUMBING
J 2
(-5750 4175);
DISPLAY 0.872340 (-5750 4175);
PAINT GREEN (-5750 4175);
DISPLAY INVISIBLE (-5750 4175);
FORCEPROP 1 LAST HDL_TAP TRUE
J 2
(-6075 4000);
DISPLAY 0.872340 (-6075 4000);
DISPLAY INVISIBLE (-6075 4000);
FORCEPROP 1 LAST PATH I275
J 2
(-5748 4125);
DISPLAY 0.872340 (-5748 4125);
PAINT GREEN (-5748 4125);
DISPLAY INVISIBLE (-5748 4125);
FORCEADD TAP..1
R 2
(-5950 4575);
FORCEPROP 3 LASTPIN (-5900 4575) SIG_NAME M_H_CPU0_SB_DQS_DN<3>
J 0
(-5890 4585);
DISPLAY 0.659574 (-5890 4585);
PAINT MONO (-5890 4585);
DISPLAY INVISIBLE (-5890 4585);
FORCEPROP 1 LASTPIN (-5900 4575) BN 3
J 2
(-5888 4583);
DISPLAY 0.489362 (-5888 4583);
PAINT GREEN (-5888 4583);
FORCEPROP 2 LAST CDS_LIB mstr_standard
J 2
(-5950 4575);
DISPLAY 0.723404 (-5950 4575);
PAINT MONO (-5950 4575);
DISPLAY INVISIBLE (-5950 4575);
FORCEPROP 1 LAST BODY_TYPE PLUMBING
J 2
(-5950 4625);
DISPLAY 0.872340 (-5950 4625);
PAINT GREEN (-5950 4625);
DISPLAY INVISIBLE (-5950 4625);
FORCEPROP 1 LAST HDL_TAP TRUE
J 2
(-6275 4450);
DISPLAY 0.872340 (-6275 4450);
DISPLAY INVISIBLE (-6275 4450);
FORCEPROP 1 LAST PATH I276
J 2
(-5948 4575);
DISPLAY 0.872340 (-5948 4575);
PAINT GREEN (-5948 4575);
DISPLAY INVISIBLE (-5948 4575);
FORCEADD TAP..1
R 2
(-5950 4475);
FORCEPROP 3 LASTPIN (-5900 4475) SIG_NAME M_H_CPU0_SB_DQS_DN<4>
J 0
(-5890 4485);
DISPLAY 0.659574 (-5890 4485);
PAINT MONO (-5890 4485);
DISPLAY INVISIBLE (-5890 4485);
FORCEPROP 1 LASTPIN (-5900 4475) BN 4
J 2
(-5888 4483);
DISPLAY 0.489362 (-5888 4483);
PAINT GREEN (-5888 4483);
FORCEPROP 2 LAST CDS_LIB mstr_standard
J 2
(-5950 4475);
DISPLAY 0.723404 (-5950 4475);
PAINT MONO (-5950 4475);
DISPLAY INVISIBLE (-5950 4475);
FORCEPROP 1 LAST BODY_TYPE PLUMBING
J 2
(-5950 4525);
DISPLAY 0.872340 (-5950 4525);
PAINT GREEN (-5950 4525);
DISPLAY INVISIBLE (-5950 4525);
FORCEPROP 1 LAST HDL_TAP TRUE
J 2
(-6275 4350);
DISPLAY 0.872340 (-6275 4350);
DISPLAY INVISIBLE (-6275 4350);
FORCEPROP 1 LAST PATH I277
J 2
(-5948 4475);
DISPLAY 0.872340 (-5948 4475);
PAINT GREEN (-5948 4475);
DISPLAY INVISIBLE (-5948 4475);
FORCEADD TAP..1
R 2
(-5950 4375);
FORCEPROP 3 LASTPIN (-5900 4375) SIG_NAME M_H_CPU0_SB_DQS_DN<5>
J 0
(-5890 4385);
DISPLAY 0.659574 (-5890 4385);
PAINT MONO (-5890 4385);
DISPLAY INVISIBLE (-5890 4385);
FORCEPROP 1 LASTPIN (-5900 4375) BN 5
J 2
(-5888 4383);
DISPLAY 0.489362 (-5888 4383);
PAINT GREEN (-5888 4383);
FORCEPROP 2 LAST CDS_LIB mstr_standard
J 2
(-5950 4375);
DISPLAY 0.723404 (-5950 4375);
PAINT MONO (-5950 4375);
DISPLAY INVISIBLE (-5950 4375);
FORCEPROP 1 LAST BODY_TYPE PLUMBING
J 2
(-5950 4425);
DISPLAY 0.872340 (-5950 4425);
PAINT GREEN (-5950 4425);
DISPLAY INVISIBLE (-5950 4425);
FORCEPROP 1 LAST HDL_TAP TRUE
J 2
(-6275 4250);
DISPLAY 0.872340 (-6275 4250);
DISPLAY INVISIBLE (-6275 4250);
FORCEPROP 1 LAST PATH I278
J 2
(-5948 4375);
DISPLAY 0.872340 (-5948 4375);
PAINT GREEN (-5948 4375);
DISPLAY INVISIBLE (-5948 4375);
FORCEADD TAP..1
R 2
(-5950 4275);
FORCEPROP 3 LASTPIN (-5900 4275) SIG_NAME M_H_CPU0_SB_DQS_DN<6>
J 0
(-5890 4285);
DISPLAY 0.659574 (-5890 4285);
PAINT MONO (-5890 4285);
DISPLAY INVISIBLE (-5890 4285);
FORCEPROP 1 LASTPIN (-5900 4275) BN 6
J 2
(-5888 4283);
DISPLAY 0.489362 (-5888 4283);
PAINT GREEN (-5888 4283);
FORCEPROP 2 LAST CDS_LIB mstr_standard
J 2
(-5950 4275);
DISPLAY 0.723404 (-5950 4275);
PAINT MONO (-5950 4275);
DISPLAY INVISIBLE (-5950 4275);
FORCEPROP 1 LAST BODY_TYPE PLUMBING
J 2
(-5950 4325);
DISPLAY 0.872340 (-5950 4325);
PAINT GREEN (-5950 4325);
DISPLAY INVISIBLE (-5950 4325);
FORCEPROP 1 LAST HDL_TAP TRUE
J 2
(-6275 4150);
DISPLAY 0.872340 (-6275 4150);
DISPLAY INVISIBLE (-6275 4150);
FORCEPROP 1 LAST PATH I279
J 2
(-5948 4275);
DISPLAY 0.872340 (-5948 4275);
PAINT GREEN (-5948 4275);
DISPLAY INVISIBLE (-5948 4275);
FORCEADD TAP..1
R 2
(-5950 4175);
FORCEPROP 3 LASTPIN (-5900 4175) SIG_NAME M_H_CPU0_SB_DQS_DN<7>
J 0
(-5890 4185);
DISPLAY 0.659574 (-5890 4185);
PAINT MONO (-5890 4185);
DISPLAY INVISIBLE (-5890 4185);
FORCEPROP 1 LASTPIN (-5900 4175) BN 7
J 2
(-5888 4183);
DISPLAY 0.489362 (-5888 4183);
PAINT GREEN (-5888 4183);
FORCEPROP 2 LAST CDS_LIB mstr_standard
J 2
(-5950 4175);
DISPLAY 0.723404 (-5950 4175);
PAINT MONO (-5950 4175);
DISPLAY INVISIBLE (-5950 4175);
FORCEPROP 1 LAST BODY_TYPE PLUMBING
J 2
(-5950 4225);
DISPLAY 0.872340 (-5950 4225);
PAINT GREEN (-5950 4225);
DISPLAY INVISIBLE (-5950 4225);
FORCEPROP 1 LAST HDL_TAP TRUE
J 2
(-6275 4050);
DISPLAY 0.872340 (-6275 4050);
DISPLAY INVISIBLE (-6275 4050);
FORCEPROP 1 LAST PATH I280
J 2
(-5948 4175);
DISPLAY 0.872340 (-5948 4175);
PAINT GREEN (-5948 4175);
DISPLAY INVISIBLE (-5948 4175);
FORCEADD OFFPAGE..3
R 2
(-6650 6000);
FORCEPROP 2 LAST $XR0 93 
J 0
(-6899 6000);
DISPLAY 0.638298 (-6899 6000);
PAINT MONO (-6899 6000);
FORCEPROP 2 LAST CDS_LIB standard
J 0
(-6650 6000);
DISPLAY INVISIBLE (-6650 6000);
FORCEPROP 1 LAST OFFPAGE TRUE
J 2
(-6975 5875);
DISPLAY 0.872340 (-6975 5875);
PAINT GREEN (-6975 5875);
DISPLAY INVISIBLE (-6975 5875);
FORCEPROP 1 LAST COMMENT_BODY TRUE
J 2
(-6600 5900);
DISPLAY 0.872340 (-6600 5900);
PAINT GREEN (-6600 5900);
DISPLAY INVISIBLE (-6600 5900);
FORCEPROP 2 LAST PATH I281
J 0
(-6925 6050);
DISPLAY 1.021277 (-6925 6050);
DISPLAY INVISIBLE (-6925 6050);
FORCEADD OFFPAGE..3
R 2
(-6650 5950);
FORCEPROP 2 LAST $XR0 93 
J 0
(-6899 5950);
DISPLAY 0.638298 (-6899 5950);
PAINT MONO (-6899 5950);
FORCEPROP 2 LAST CDS_LIB standard
J 0
(-6650 5950);
DISPLAY INVISIBLE (-6650 5950);
FORCEPROP 1 LAST OFFPAGE TRUE
J 2
(-6975 5825);
DISPLAY 0.872340 (-6975 5825);
PAINT GREEN (-6975 5825);
DISPLAY INVISIBLE (-6975 5825);
FORCEPROP 1 LAST COMMENT_BODY TRUE
J 2
(-6600 5850);
DISPLAY 0.872340 (-6600 5850);
PAINT GREEN (-6600 5850);
DISPLAY INVISIBLE (-6600 5850);
FORCEPROP 2 LAST PATH I282
J 0
(-6925 6000);
DISPLAY 1.021277 (-6925 6000);
DISPLAY INVISIBLE (-6925 6000);
FORCEADD OFFPAGE..3
R 2
(-6650 4950);
FORCEPROP 2 LAST $XR0 93 
J 0
(-6899 4950);
DISPLAY 0.638298 (-6899 4950);
PAINT MONO (-6899 4950);
FORCEPROP 2 LAST CDS_LIB standard
J 0
(-6650 4950);
DISPLAY INVISIBLE (-6650 4950);
FORCEPROP 1 LAST OFFPAGE TRUE
J 2
(-6975 4825);
DISPLAY 0.872340 (-6975 4825);
PAINT GREEN (-6975 4825);
DISPLAY INVISIBLE (-6975 4825);
FORCEPROP 1 LAST COMMENT_BODY TRUE
J 2
(-6600 4850);
DISPLAY 0.872340 (-6600 4850);
PAINT GREEN (-6600 4850);
DISPLAY INVISIBLE (-6600 4850);
FORCEPROP 2 LAST PATH I283
J 0
(-6925 5000);
DISPLAY 1.021277 (-6925 5000);
DISPLAY INVISIBLE (-6925 5000);
FORCEADD OFFPAGE..3
R 2
(-6650 4900);
FORCEPROP 2 LAST $XR0 93 
J 0
(-6899 4900);
DISPLAY 0.638298 (-6899 4900);
PAINT MONO (-6899 4900);
FORCEPROP 2 LAST CDS_LIB standard
J 0
(-6650 4900);
DISPLAY INVISIBLE (-6650 4900);
FORCEPROP 1 LAST OFFPAGE TRUE
J 2
(-6975 4775);
DISPLAY 0.872340 (-6975 4775);
PAINT GREEN (-6975 4775);
DISPLAY INVISIBLE (-6975 4775);
FORCEPROP 1 LAST COMMENT_BODY TRUE
J 2
(-6600 4800);
DISPLAY 0.872340 (-6600 4800);
PAINT GREEN (-6600 4800);
DISPLAY INVISIBLE (-6600 4800);
FORCEPROP 2 LAST PATH I284
J 0
(-6925 4950);
DISPLAY 1.021277 (-6925 4950);
DISPLAY INVISIBLE (-6925 4950);
FORCEADD TAP..1
R 2
(-5750 4025);
FORCEPROP 3 LASTPIN (-5700 4025) SIG_NAME M_H_CPU0_SB_DQS_DP<9>
J 0
(-5690 4035);
DISPLAY 0.659574 (-5690 4035);
PAINT MONO (-5690 4035);
DISPLAY INVISIBLE (-5690 4035);
FORCEPROP 1 LASTPIN (-5700 4025) BN 9
J 2
(-5688 4033);
DISPLAY 0.489362 (-5688 4033);
PAINT GREEN (-5688 4033);
FORCEPROP 2 LAST CDS_LIB mstr_standard
J 2
(-5750 4025);
DISPLAY 0.723404 (-5750 4025);
PAINT MONO (-5750 4025);
DISPLAY INVISIBLE (-5750 4025);
FORCEPROP 1 LAST BODY_TYPE PLUMBING
J 2
(-5750 4075);
DISPLAY 0.872340 (-5750 4075);
PAINT GREEN (-5750 4075);
DISPLAY INVISIBLE (-5750 4075);
FORCEPROP 1 LAST HDL_TAP TRUE
J 2
(-6075 3900);
DISPLAY 0.872340 (-6075 3900);
DISPLAY INVISIBLE (-6075 3900);
FORCEPROP 1 LAST PATH I285
J 2
(-5748 4025);
DISPLAY 0.872340 (-5748 4025);
PAINT GREEN (-5748 4025);
DISPLAY INVISIBLE (-5748 4025);
FORCEADD TAP..1
R 2
(-5950 4075);
FORCEPROP 3 LASTPIN (-5900 4075) SIG_NAME M_H_CPU0_SB_DQS_DN<8>
J 0
(-5890 4085);
DISPLAY 0.659574 (-5890 4085);
PAINT MONO (-5890 4085);
DISPLAY INVISIBLE (-5890 4085);
FORCEPROP 1 LASTPIN (-5900 4075) BN 8
J 2
(-5888 4083);
DISPLAY 0.489362 (-5888 4083);
PAINT GREEN (-5888 4083);
FORCEPROP 2 LAST CDS_LIB mstr_standard
J 2
(-5950 4075);
DISPLAY 0.723404 (-5950 4075);
PAINT MONO (-5950 4075);
DISPLAY INVISIBLE (-5950 4075);
FORCEPROP 1 LAST BODY_TYPE PLUMBING
J 2
(-5950 4125);
DISPLAY 0.872340 (-5950 4125);
PAINT GREEN (-5950 4125);
DISPLAY INVISIBLE (-5950 4125);
FORCEPROP 1 LAST HDL_TAP TRUE
J 2
(-6275 3950);
DISPLAY 0.872340 (-6275 3950);
DISPLAY INVISIBLE (-6275 3950);
FORCEPROP 1 LAST PATH I286
J 2
(-5948 4075);
DISPLAY 0.872340 (-5948 4075);
PAINT GREEN (-5948 4075);
DISPLAY INVISIBLE (-5948 4075);
FORCEADD TAP..1
R 2
(-5950 3975);
FORCEPROP 3 LASTPIN (-5900 3975) SIG_NAME M_H_CPU0_SB_DQS_DN<9>
J 0
(-5890 3985);
DISPLAY 0.659574 (-5890 3985);
PAINT MONO (-5890 3985);
DISPLAY INVISIBLE (-5890 3985);
FORCEPROP 1 LASTPIN (-5900 3975) BN 9
J 2
(-5888 3983);
DISPLAY 0.489362 (-5888 3983);
PAINT GREEN (-5888 3983);
FORCEPROP 2 LAST CDS_LIB mstr_standard
J 2
(-5950 3975);
DISPLAY 0.723404 (-5950 3975);
PAINT MONO (-5950 3975);
DISPLAY INVISIBLE (-5950 3975);
FORCEPROP 1 LAST BODY_TYPE PLUMBING
J 2
(-5950 4025);
DISPLAY 0.872340 (-5950 4025);
PAINT GREEN (-5950 4025);
DISPLAY INVISIBLE (-5950 4025);
FORCEPROP 1 LAST HDL_TAP TRUE
J 2
(-6275 3850);
DISPLAY 0.872340 (-6275 3850);
DISPLAY INVISIBLE (-6275 3850);
FORCEPROP 1 LAST PATH I287
J 2
(-5948 3975);
DISPLAY 0.872340 (-5948 3975);
PAINT GREEN (-5948 3975);
DISPLAY INVISIBLE (-5948 3975);
FORCEADD TAP..1
R 2
(-5950 3825);
FORCEPROP 3 LASTPIN (-5900 3825) SIG_NAME M_H_CPU0_SA_CA<0>
J 0
(-5890 3835);
DISPLAY 0.659574 (-5890 3835);
PAINT MONO (-5890 3835);
DISPLAY INVISIBLE (-5890 3835);
FORCEPROP 1 LASTPIN (-5900 3825) BN 0
J 2
(-5888 3833);
DISPLAY 0.489362 (-5888 3833);
PAINT GREEN (-5888 3833);
FORCEPROP 2 LAST CDS_LIB mstr_standard
J 0
(-5950 3825);
DISPLAY 0.723404 (-5950 3825);
PAINT MONO (-5950 3825);
DISPLAY INVISIBLE (-5950 3825);
FORCEPROP 1 LAST BODY_TYPE PLUMBING
J 2
(-5950 3875);
DISPLAY 0.872340 (-5950 3875);
PAINT GREEN (-5950 3875);
DISPLAY INVISIBLE (-5950 3875);
FORCEPROP 1 LAST HDL_TAP TRUE
J 2
(-6275 3700);
DISPLAY 0.872340 (-6275 3700);
DISPLAY INVISIBLE (-6275 3700);
FORCEPROP 1 LAST PATH I288
J 2
(-5948 3825);
DISPLAY 0.872340 (-5948 3825);
PAINT GREEN (-5948 3825);
DISPLAY INVISIBLE (-5948 3825);
FORCEADD TAP..1
R 2
(-5950 3775);
FORCEPROP 3 LASTPIN (-5900 3775) SIG_NAME M_H_CPU0_SA_CA<1>
J 0
(-5890 3785);
DISPLAY 0.659574 (-5890 3785);
PAINT MONO (-5890 3785);
DISPLAY INVISIBLE (-5890 3785);
FORCEPROP 1 LASTPIN (-5900 3775) BN 1
J 2
(-5888 3783);
DISPLAY 0.489362 (-5888 3783);
PAINT GREEN (-5888 3783);
FORCEPROP 2 LAST CDS_LIB mstr_standard
J 0
(-5950 3775);
DISPLAY 0.723404 (-5950 3775);
PAINT MONO (-5950 3775);
DISPLAY INVISIBLE (-5950 3775);
FORCEPROP 1 LAST BODY_TYPE PLUMBING
J 2
(-5950 3825);
DISPLAY 0.872340 (-5950 3825);
PAINT GREEN (-5950 3825);
DISPLAY INVISIBLE (-5950 3825);
FORCEPROP 1 LAST HDL_TAP TRUE
J 2
(-6275 3650);
DISPLAY 0.872340 (-6275 3650);
DISPLAY INVISIBLE (-6275 3650);
FORCEPROP 1 LAST PATH I289
J 2
(-5948 3775);
DISPLAY 0.872340 (-5948 3775);
PAINT GREEN (-5948 3775);
DISPLAY INVISIBLE (-5948 3775);
FORCEADD TAP..1
R 2
(-5950 3725);
FORCEPROP 3 LASTPIN (-5900 3725) SIG_NAME M_H_CPU0_SA_CA<2>
J 0
(-5890 3735);
DISPLAY 0.659574 (-5890 3735);
PAINT MONO (-5890 3735);
DISPLAY INVISIBLE (-5890 3735);
FORCEPROP 1 LASTPIN (-5900 3725) BN 2
J 2
(-5888 3733);
DISPLAY 0.489362 (-5888 3733);
PAINT GREEN (-5888 3733);
FORCEPROP 2 LAST CDS_LIB mstr_standard
J 0
(-5950 3725);
DISPLAY 0.723404 (-5950 3725);
PAINT MONO (-5950 3725);
DISPLAY INVISIBLE (-5950 3725);
FORCEPROP 1 LAST BODY_TYPE PLUMBING
J 2
(-5950 3775);
DISPLAY 0.872340 (-5950 3775);
PAINT GREEN (-5950 3775);
DISPLAY INVISIBLE (-5950 3775);
FORCEPROP 1 LAST HDL_TAP TRUE
J 2
(-6275 3600);
DISPLAY 0.872340 (-6275 3600);
DISPLAY INVISIBLE (-6275 3600);
FORCEPROP 1 LAST PATH I290
J 2
(-5948 3725);
DISPLAY 0.872340 (-5948 3725);
PAINT GREEN (-5948 3725);
DISPLAY INVISIBLE (-5948 3725);
FORCEADD TAP..1
R 2
(-5950 3675);
FORCEPROP 3 LASTPIN (-5900 3675) SIG_NAME M_H_CPU0_SA_CA<3>
J 0
(-5890 3685);
DISPLAY 0.659574 (-5890 3685);
PAINT MONO (-5890 3685);
DISPLAY INVISIBLE (-5890 3685);
FORCEPROP 1 LASTPIN (-5900 3675) BN 3
J 2
(-5888 3683);
DISPLAY 0.489362 (-5888 3683);
PAINT GREEN (-5888 3683);
FORCEPROP 2 LAST CDS_LIB mstr_standard
J 0
(-5950 3675);
DISPLAY 0.723404 (-5950 3675);
PAINT MONO (-5950 3675);
DISPLAY INVISIBLE (-5950 3675);
FORCEPROP 1 LAST BODY_TYPE PLUMBING
J 2
(-5950 3725);
DISPLAY 0.872340 (-5950 3725);
PAINT GREEN (-5950 3725);
DISPLAY INVISIBLE (-5950 3725);
FORCEPROP 1 LAST HDL_TAP TRUE
J 2
(-6275 3550);
DISPLAY 0.872340 (-6275 3550);
DISPLAY INVISIBLE (-6275 3550);
FORCEPROP 1 LAST PATH I291
J 2
(-5948 3675);
DISPLAY 0.872340 (-5948 3675);
PAINT GREEN (-5948 3675);
DISPLAY INVISIBLE (-5948 3675);
FORCEADD TAP..1
R 2
(-5950 3625);
FORCEPROP 3 LASTPIN (-5900 3625) SIG_NAME M_H_CPU0_SA_CA<4>
J 0
(-5890 3635);
DISPLAY 0.659574 (-5890 3635);
PAINT MONO (-5890 3635);
DISPLAY INVISIBLE (-5890 3635);
FORCEPROP 1 LASTPIN (-5900 3625) BN 4
J 2
(-5888 3633);
DISPLAY 0.489362 (-5888 3633);
PAINT GREEN (-5888 3633);
FORCEPROP 2 LAST CDS_LIB mstr_standard
J 0
(-5950 3625);
DISPLAY 0.723404 (-5950 3625);
PAINT MONO (-5950 3625);
DISPLAY INVISIBLE (-5950 3625);
FORCEPROP 1 LAST BODY_TYPE PLUMBING
J 2
(-5950 3675);
DISPLAY 0.872340 (-5950 3675);
PAINT GREEN (-5950 3675);
DISPLAY INVISIBLE (-5950 3675);
FORCEPROP 1 LAST HDL_TAP TRUE
J 2
(-6275 3500);
DISPLAY 0.872340 (-6275 3500);
DISPLAY INVISIBLE (-6275 3500);
FORCEPROP 1 LAST PATH I292
J 2
(-5948 3625);
DISPLAY 0.872340 (-5948 3625);
PAINT GREEN (-5948 3625);
DISPLAY INVISIBLE (-5948 3625);
FORCEADD TAP..1
R 2
(-5950 3575);
FORCEPROP 3 LASTPIN (-5900 3575) SIG_NAME M_H_CPU0_SA_CA<5>
J 0
(-5890 3585);
DISPLAY 0.659574 (-5890 3585);
PAINT MONO (-5890 3585);
DISPLAY INVISIBLE (-5890 3585);
FORCEPROP 1 LASTPIN (-5900 3575) BN 5
J 2
(-5888 3583);
DISPLAY 0.489362 (-5888 3583);
PAINT GREEN (-5888 3583);
FORCEPROP 2 LAST CDS_LIB mstr_standard
J 0
(-5950 3575);
DISPLAY 0.723404 (-5950 3575);
PAINT MONO (-5950 3575);
DISPLAY INVISIBLE (-5950 3575);
FORCEPROP 1 LAST BODY_TYPE PLUMBING
J 2
(-5950 3625);
DISPLAY 0.872340 (-5950 3625);
PAINT GREEN (-5950 3625);
DISPLAY INVISIBLE (-5950 3625);
FORCEPROP 1 LAST HDL_TAP TRUE
J 2
(-6275 3450);
DISPLAY 0.872340 (-6275 3450);
DISPLAY INVISIBLE (-6275 3450);
FORCEPROP 1 LAST PATH I293
J 2
(-5948 3575);
DISPLAY 0.872340 (-5948 3575);
PAINT GREEN (-5948 3575);
DISPLAY INVISIBLE (-5948 3575);
FORCEADD TAP..1
R 2
(-5950 3525);
FORCEPROP 3 LASTPIN (-5900 3525) SIG_NAME M_H_CPU0_SA_CA<6>
J 0
(-5890 3535);
DISPLAY 0.659574 (-5890 3535);
PAINT MONO (-5890 3535);
DISPLAY INVISIBLE (-5890 3535);
FORCEPROP 1 LASTPIN (-5900 3525) BN 6
J 2
(-5888 3533);
DISPLAY 0.489362 (-5888 3533);
PAINT GREEN (-5888 3533);
FORCEPROP 2 LAST CDS_LIB mstr_standard
J 0
(-5950 3525);
DISPLAY 0.723404 (-5950 3525);
PAINT MONO (-5950 3525);
DISPLAY INVISIBLE (-5950 3525);
FORCEPROP 1 LAST BODY_TYPE PLUMBING
J 2
(-5950 3575);
DISPLAY 0.872340 (-5950 3575);
PAINT GREEN (-5950 3575);
DISPLAY INVISIBLE (-5950 3575);
FORCEPROP 1 LAST HDL_TAP TRUE
J 2
(-6275 3400);
DISPLAY 0.872340 (-6275 3400);
DISPLAY INVISIBLE (-6275 3400);
FORCEPROP 1 LAST PATH I294
J 2
(-5948 3525);
DISPLAY 0.872340 (-5948 3525);
PAINT GREEN (-5948 3525);
DISPLAY INVISIBLE (-5948 3525);
FORCEADD TAP..1
R 2
(-5950 3325);
FORCEPROP 3 LASTPIN (-5900 3325) SIG_NAME M_H_CPU0_SB_CA<2>
J 0
(-5890 3335);
DISPLAY 0.659574 (-5890 3335);
PAINT MONO (-5890 3335);
DISPLAY INVISIBLE (-5890 3335);
FORCEPROP 1 LASTPIN (-5900 3325) BN 2
J 2
(-5888 3333);
DISPLAY 0.489362 (-5888 3333);
PAINT GREEN (-5888 3333);
FORCEPROP 2 LAST CDS_LIB mstr_standard
J 0
(-5950 3325);
DISPLAY 0.723404 (-5950 3325);
PAINT MONO (-5950 3325);
DISPLAY INVISIBLE (-5950 3325);
FORCEPROP 1 LAST BODY_TYPE PLUMBING
J 2
(-5950 3375);
DISPLAY 0.872340 (-5950 3375);
PAINT GREEN (-5950 3375);
DISPLAY INVISIBLE (-5950 3375);
FORCEPROP 1 LAST HDL_TAP TRUE
J 2
(-6275 3200);
DISPLAY 0.872340 (-6275 3200);
DISPLAY INVISIBLE (-6275 3200);
FORCEPROP 1 LAST PATH I295
J 2
(-5948 3325);
DISPLAY 0.872340 (-5948 3325);
PAINT GREEN (-5948 3325);
DISPLAY INVISIBLE (-5948 3325);
FORCEADD TAP..1
R 2
(-5950 3425);
FORCEPROP 3 LASTPIN (-5900 3425) SIG_NAME M_H_CPU0_SB_CA<0>
J 0
(-5890 3435);
DISPLAY 0.659574 (-5890 3435);
PAINT MONO (-5890 3435);
DISPLAY INVISIBLE (-5890 3435);
FORCEPROP 1 LASTPIN (-5900 3425) BN 0
J 2
(-5888 3433);
DISPLAY 0.489362 (-5888 3433);
PAINT GREEN (-5888 3433);
FORCEPROP 2 LAST CDS_LIB mstr_standard
J 0
(-5950 3425);
DISPLAY 0.723404 (-5950 3425);
PAINT MONO (-5950 3425);
DISPLAY INVISIBLE (-5950 3425);
FORCEPROP 1 LAST BODY_TYPE PLUMBING
J 2
(-5950 3475);
DISPLAY 0.872340 (-5950 3475);
PAINT GREEN (-5950 3475);
DISPLAY INVISIBLE (-5950 3475);
FORCEPROP 1 LAST HDL_TAP TRUE
J 2
(-6275 3300);
DISPLAY 0.872340 (-6275 3300);
DISPLAY INVISIBLE (-6275 3300);
FORCEPROP 1 LAST PATH I296
J 2
(-5948 3425);
DISPLAY 0.872340 (-5948 3425);
PAINT GREEN (-5948 3425);
DISPLAY INVISIBLE (-5948 3425);
FORCEADD TAP..1
R 2
(-5950 3375);
FORCEPROP 3 LASTPIN (-5900 3375) SIG_NAME M_H_CPU0_SB_CA<1>
J 0
(-5890 3385);
DISPLAY 0.659574 (-5890 3385);
PAINT MONO (-5890 3385);
DISPLAY INVISIBLE (-5890 3385);
FORCEPROP 1 LASTPIN (-5900 3375) BN 1
J 2
(-5888 3383);
DISPLAY 0.489362 (-5888 3383);
PAINT GREEN (-5888 3383);
FORCEPROP 2 LAST CDS_LIB mstr_standard
J 0
(-5950 3375);
DISPLAY 0.723404 (-5950 3375);
PAINT MONO (-5950 3375);
DISPLAY INVISIBLE (-5950 3375);
FORCEPROP 1 LAST BODY_TYPE PLUMBING
J 2
(-5950 3425);
DISPLAY 0.872340 (-5950 3425);
PAINT GREEN (-5950 3425);
DISPLAY INVISIBLE (-5950 3425);
FORCEPROP 1 LAST HDL_TAP TRUE
J 2
(-6275 3250);
DISPLAY 0.872340 (-6275 3250);
DISPLAY INVISIBLE (-6275 3250);
FORCEPROP 1 LAST PATH I297
J 2
(-5948 3375);
DISPLAY 0.872340 (-5948 3375);
PAINT GREEN (-5948 3375);
DISPLAY INVISIBLE (-5948 3375);
FORCEADD TAP..1
R 2
(-5950 3275);
FORCEPROP 3 LASTPIN (-5900 3275) SIG_NAME M_H_CPU0_SB_CA<3>
J 0
(-5890 3285);
DISPLAY 0.659574 (-5890 3285);
PAINT MONO (-5890 3285);
DISPLAY INVISIBLE (-5890 3285);
FORCEPROP 1 LASTPIN (-5900 3275) BN 3
J 2
(-5888 3283);
DISPLAY 0.489362 (-5888 3283);
PAINT GREEN (-5888 3283);
FORCEPROP 2 LAST CDS_LIB mstr_standard
J 0
(-5950 3275);
DISPLAY 0.723404 (-5950 3275);
PAINT MONO (-5950 3275);
DISPLAY INVISIBLE (-5950 3275);
FORCEPROP 1 LAST BODY_TYPE PLUMBING
J 2
(-5950 3325);
DISPLAY 0.872340 (-5950 3325);
PAINT GREEN (-5950 3325);
DISPLAY INVISIBLE (-5950 3325);
FORCEPROP 1 LAST HDL_TAP TRUE
J 2
(-6275 3150);
DISPLAY 0.872340 (-6275 3150);
DISPLAY INVISIBLE (-6275 3150);
FORCEPROP 1 LAST PATH I298
J 2
(-5948 3275);
DISPLAY 0.872340 (-5948 3275);
PAINT GREEN (-5948 3275);
DISPLAY INVISIBLE (-5948 3275);
FORCEADD TAP..1
R 2
(-5950 3225);
FORCEPROP 3 LASTPIN (-5900 3225) SIG_NAME M_H_CPU0_SB_CA<4>
J 0
(-5890 3235);
DISPLAY 0.659574 (-5890 3235);
PAINT MONO (-5890 3235);
DISPLAY INVISIBLE (-5890 3235);
FORCEPROP 1 LASTPIN (-5900 3225) BN 4
J 2
(-5888 3233);
DISPLAY 0.489362 (-5888 3233);
PAINT GREEN (-5888 3233);
FORCEPROP 2 LAST CDS_LIB mstr_standard
J 0
(-5950 3225);
DISPLAY 0.723404 (-5950 3225);
PAINT MONO (-5950 3225);
DISPLAY INVISIBLE (-5950 3225);
FORCEPROP 1 LAST BODY_TYPE PLUMBING
J 2
(-5950 3275);
DISPLAY 0.872340 (-5950 3275);
PAINT GREEN (-5950 3275);
DISPLAY INVISIBLE (-5950 3275);
FORCEPROP 1 LAST HDL_TAP TRUE
J 2
(-6275 3100);
DISPLAY 0.872340 (-6275 3100);
DISPLAY INVISIBLE (-6275 3100);
FORCEPROP 1 LAST PATH I299
J 2
(-5948 3225);
DISPLAY 0.872340 (-5948 3225);
PAINT GREEN (-5948 3225);
DISPLAY INVISIBLE (-5948 3225);
FORCEADD TAP..1
R 2
(-5950 3125);
FORCEPROP 3 LASTPIN (-5900 3125) SIG_NAME M_H_CPU0_SB_CA<6>
J 0
(-5890 3135);
DISPLAY 0.659574 (-5890 3135);
PAINT MONO (-5890 3135);
DISPLAY INVISIBLE (-5890 3135);
FORCEPROP 1 LASTPIN (-5900 3125) BN 6
J 2
(-5888 3133);
DISPLAY 0.489362 (-5888 3133);
PAINT GREEN (-5888 3133);
FORCEPROP 2 LAST CDS_LIB mstr_standard
J 0
(-5950 3125);
DISPLAY 0.723404 (-5950 3125);
PAINT MONO (-5950 3125);
DISPLAY INVISIBLE (-5950 3125);
FORCEPROP 1 LAST BODY_TYPE PLUMBING
J 2
(-5950 3175);
DISPLAY 0.872340 (-5950 3175);
PAINT GREEN (-5950 3175);
DISPLAY INVISIBLE (-5950 3175);
FORCEPROP 1 LAST HDL_TAP TRUE
J 2
(-6275 3000);
DISPLAY 0.872340 (-6275 3000);
DISPLAY INVISIBLE (-6275 3000);
FORCEPROP 1 LAST PATH I300
J 2
(-5948 3125);
DISPLAY 0.872340 (-5948 3125);
PAINT GREEN (-5948 3125);
DISPLAY INVISIBLE (-5948 3125);
FORCEADD TAP..1
R 2
(-5950 3175);
FORCEPROP 3 LASTPIN (-5900 3175) SIG_NAME M_H_CPU0_SB_CA<5>
J 0
(-5890 3185);
DISPLAY 0.659574 (-5890 3185);
PAINT MONO (-5890 3185);
DISPLAY INVISIBLE (-5890 3185);
FORCEPROP 1 LASTPIN (-5900 3175) BN 5
J 2
(-5888 3183);
DISPLAY 0.489362 (-5888 3183);
PAINT GREEN (-5888 3183);
FORCEPROP 2 LAST CDS_LIB mstr_standard
J 0
(-5950 3175);
DISPLAY 0.723404 (-5950 3175);
PAINT MONO (-5950 3175);
DISPLAY INVISIBLE (-5950 3175);
FORCEPROP 1 LAST BODY_TYPE PLUMBING
J 2
(-5950 3225);
DISPLAY 0.872340 (-5950 3225);
PAINT GREEN (-5950 3225);
DISPLAY INVISIBLE (-5950 3225);
FORCEPROP 1 LAST HDL_TAP TRUE
J 2
(-6275 3050);
DISPLAY 0.872340 (-6275 3050);
DISPLAY INVISIBLE (-6275 3050);
FORCEPROP 1 LAST PATH I301
J 2
(-5948 3175);
DISPLAY 0.872340 (-5948 3175);
PAINT GREEN (-5948 3175);
DISPLAY INVISIBLE (-5948 3175);
FORCEADD OFFPAGE..2
R 2
(-6550 3850);
FORCEPROP 2 LAST $XR0 93 
J 0
(-6774 3850);
DISPLAY 0.638298 (-6774 3850);
PAINT MONO (-6774 3850);
FORCEPROP 2 LAST CDS_LIB standard
J 0
(-6550 3850);
DISPLAY INVISIBLE (-6550 3850);
FORCEPROP 1 LAST OFFPAGE TRUE
J 2
(-6875 3725);
DISPLAY 0.872340 (-6875 3725);
PAINT GREEN (-6875 3725);
DISPLAY INVISIBLE (-6875 3725);
FORCEPROP 1 LAST COMMENT_BODY TRUE
J 2
(-6505 3755);
DISPLAY 0.872340 (-6505 3755);
PAINT GREEN (-6505 3755);
DISPLAY INVISIBLE (-6505 3755);
FORCEPROP 2 LAST PATH I302
J 0
(-6800 3900);
DISPLAY 1.021277 (-6800 3900);
DISPLAY INVISIBLE (-6800 3900);
FORCEADD OFFPAGE..2
R 2
(-6550 3450);
FORCEPROP 2 LAST $XR0 93 
J 0
(-6774 3450);
DISPLAY 0.638298 (-6774 3450);
PAINT MONO (-6774 3450);
FORCEPROP 2 LAST CDS_LIB standard
J 0
(-6550 3450);
DISPLAY INVISIBLE (-6550 3450);
FORCEPROP 1 LAST OFFPAGE TRUE
J 2
(-6875 3325);
DISPLAY 0.872340 (-6875 3325);
PAINT GREEN (-6875 3325);
DISPLAY INVISIBLE (-6875 3325);
FORCEPROP 1 LAST COMMENT_BODY TRUE
J 2
(-6505 3355);
DISPLAY 0.872340 (-6505 3355);
PAINT GREEN (-6505 3355);
DISPLAY INVISIBLE (-6505 3355);
FORCEPROP 2 LAST PATH I303
J 0
(-6800 3500);
DISPLAY 1.021277 (-6800 3500);
DISPLAY INVISIBLE (-6800 3500);
FORCEADD OFFPAGE..2
R 2
(-6550 2975);
FORCEPROP 2 LAST $XR0 93 
J 0
(-6774 2975);
DISPLAY 0.638298 (-6774 2975);
PAINT MONO (-6774 2975);
FORCEPROP 2 LAST CDS_LIB standard
J 0
(-6550 2975);
DISPLAY INVISIBLE (-6550 2975);
FORCEPROP 1 LAST OFFPAGE TRUE
J 2
(-6875 2850);
DISPLAY 0.872340 (-6875 2850);
PAINT GREEN (-6875 2850);
DISPLAY INVISIBLE (-6875 2850);
FORCEPROP 1 LAST COMMENT_BODY TRUE
J 2
(-6505 2880);
DISPLAY 0.872340 (-6505 2880);
PAINT GREEN (-6505 2880);
DISPLAY INVISIBLE (-6505 2880);
FORCEPROP 2 LAST PATH I304
J 0
(-6800 3025);
DISPLAY 1.021277 (-6800 3025);
DISPLAY INVISIBLE (-6800 3025);
FORCEADD OFFPAGE..2
R 2
(-6550 2925);
FORCEPROP 2 LAST $XR0 93 
J 0
(-6774 2925);
DISPLAY 0.638298 (-6774 2925);
PAINT MONO (-6774 2925);
FORCEPROP 2 LAST CDS_LIB standard
J 0
(-6550 2925);
DISPLAY INVISIBLE (-6550 2925);
FORCEPROP 1 LAST OFFPAGE TRUE
J 2
(-6875 2800);
DISPLAY 0.872340 (-6875 2800);
PAINT GREEN (-6875 2800);
DISPLAY INVISIBLE (-6875 2800);
FORCEPROP 1 LAST COMMENT_BODY TRUE
J 2
(-6505 2830);
DISPLAY 0.872340 (-6505 2830);
PAINT GREEN (-6505 2830);
DISPLAY INVISIBLE (-6505 2830);
FORCEPROP 2 LAST PATH I305
J 0
(-6800 2975);
DISPLAY 1.021277 (-6800 2975);
DISPLAY INVISIBLE (-6800 2975);
FORCEADD OFFPAGE..2
R 2
(-6550 2825);
FORCEPROP 2 LAST $XR0 93 
J 0
(-6774 2825);
DISPLAY 0.638298 (-6774 2825);
PAINT MONO (-6774 2825);
FORCEPROP 2 LAST CDS_LIB standard
J 0
(-6550 2825);
DISPLAY INVISIBLE (-6550 2825);
FORCEPROP 1 LAST OFFPAGE TRUE
J 2
(-6875 2700);
DISPLAY 0.872340 (-6875 2700);
PAINT GREEN (-6875 2700);
DISPLAY INVISIBLE (-6875 2700);
FORCEPROP 1 LAST COMMENT_BODY TRUE
J 2
(-6505 2730);
DISPLAY 0.872340 (-6505 2730);
PAINT GREEN (-6505 2730);
DISPLAY INVISIBLE (-6505 2730);
FORCEPROP 2 LAST PATH I306
J 0
(-6800 2875);
DISPLAY 1.021277 (-6800 2875);
DISPLAY INVISIBLE (-6800 2875);
FORCEADD OFFPAGE..2
R 2
(-6550 2775);
FORCEPROP 2 LAST $XR0 93 
J 0
(-6774 2775);
DISPLAY 0.638298 (-6774 2775);
PAINT MONO (-6774 2775);
FORCEPROP 2 LAST CDS_LIB standard
J 0
(-6550 2775);
DISPLAY INVISIBLE (-6550 2775);
FORCEPROP 1 LAST OFFPAGE TRUE
J 2
(-6875 2650);
DISPLAY 0.872340 (-6875 2650);
PAINT GREEN (-6875 2650);
DISPLAY INVISIBLE (-6875 2650);
FORCEPROP 1 LAST COMMENT_BODY TRUE
J 2
(-6505 2680);
DISPLAY 0.872340 (-6505 2680);
PAINT GREEN (-6505 2680);
DISPLAY INVISIBLE (-6505 2680);
FORCEPROP 2 LAST PATH I307
J 0
(-6800 2825);
DISPLAY 1.021277 (-6800 2825);
DISPLAY INVISIBLE (-6800 2825);
FORCEADD OFFPAGE..1
(-6550 2675);
FORCEPROP 2 LAST $XR0 93 
J 0
(-6801 2675);
DISPLAY 0.638298 (-6801 2675);
PAINT MONO (-6801 2675);
FORCEPROP 2 LAST CDS_LIB standard
J 0
(-6550 2675);
DISPLAY INVISIBLE (-6550 2675);
FORCEPROP 1 LAST OFFPAGE TRUE
J 0
(-6225 2550);
DISPLAY 0.872340 (-6225 2550);
PAINT GREEN (-6225 2550);
DISPLAY INVISIBLE (-6225 2550);
FORCEPROP 1 LAST COMMENT_BODY TRUE
J 0
(-6425 2575);
DISPLAY 0.872340 (-6425 2575);
PAINT GREEN (-6425 2575);
DISPLAY INVISIBLE (-6425 2575);
FORCEPROP 2 LAST PATH I308
J 0
(-6825 2725);
DISPLAY 1.021277 (-6825 2725);
DISPLAY INVISIBLE (-6825 2725);
FORCEADD OFFPAGE..5
(-6550 2575);
FORCEPROP 2 LAST $XR0 93 
J 0
(-6774 2575);
DISPLAY 0.638298 (-6774 2575);
PAINT MONO (-6774 2575);
FORCEPROP 2 LAST CDS_LIB mstr_standard
J 0
(-6550 2575);
DISPLAY INVISIBLE (-6550 2575);
FORCEPROP 1 LAST OFFPAGE TRUE
J 0
(-6225 2450);
DISPLAY 0.872340 (-6225 2450);
PAINT GREEN (-6225 2450);
DISPLAY INVISIBLE (-6225 2450);
FORCEPROP 1 LAST COMMENT_BODY TRUE
J 0
(-6450 2500);
DISPLAY 0.872340 (-6450 2500);
PAINT GREEN (-6450 2500);
DISPLAY INVISIBLE (-6450 2500);
FORCEPROP 2 LAST PATH I309
J 0
(-6800 2625);
DISPLAY 1.021277 (-6800 2625);
DISPLAY INVISIBLE (-6800 2625);
FORCEADD OFFPAGE..2
R 2
(-6550 2425);
FORCEPROP 2 LAST $XR0 93 
J 0
(-6774 2425);
DISPLAY 0.638298 (-6774 2425);
PAINT MONO (-6774 2425);
FORCEPROP 2 LAST CDS_LIB standard
J 0
(-6550 2425);
DISPLAY INVISIBLE (-6550 2425);
FORCEPROP 1 LAST OFFPAGE TRUE
J 2
(-6875 2300);
DISPLAY 0.872340 (-6875 2300);
PAINT GREEN (-6875 2300);
DISPLAY INVISIBLE (-6875 2300);
FORCEPROP 1 LAST COMMENT_BODY TRUE
J 2
(-6505 2330);
DISPLAY 0.872340 (-6505 2330);
PAINT GREEN (-6505 2330);
DISPLAY INVISIBLE (-6505 2330);
FORCEPROP 2 LAST PATH I310
J 0
(-6800 2475);
DISPLAY 1.021277 (-6800 2475);
DISPLAY INVISIBLE (-6800 2475);
FORCEADD OFFPAGE..2
R 2
(-6550 2475);
FORCEPROP 2 LAST $XR0 93 
J 0
(-6774 2475);
DISPLAY 0.638298 (-6774 2475);
PAINT MONO (-6774 2475);
FORCEPROP 2 LAST CDS_LIB standard
J 0
(-6550 2475);
DISPLAY INVISIBLE (-6550 2475);
FORCEPROP 1 LAST OFFPAGE TRUE
J 2
(-6875 2350);
DISPLAY 0.872340 (-6875 2350);
PAINT GREEN (-6875 2350);
DISPLAY INVISIBLE (-6875 2350);
FORCEPROP 1 LAST COMMENT_BODY TRUE
J 2
(-6505 2380);
DISPLAY 0.872340 (-6505 2380);
PAINT GREEN (-6505 2380);
DISPLAY INVISIBLE (-6505 2380);
FORCEPROP 2 LAST PATH I311
J 0
(-6800 2525);
DISPLAY 1.021277 (-6800 2525);
DISPLAY INVISIBLE (-6800 2525);
FORCEADD OFFPAGE..1
(-6550 2325);
FORCEPROP 2 LAST $XR0 93 
J 0
(-6801 2325);
DISPLAY 0.638298 (-6801 2325);
PAINT MONO (-6801 2325);
FORCEPROP 2 LAST CDS_LIB standard
J 0
(-6550 2325);
DISPLAY INVISIBLE (-6550 2325);
FORCEPROP 1 LAST OFFPAGE TRUE
J 0
(-6225 2200);
DISPLAY 0.872340 (-6225 2200);
PAINT GREEN (-6225 2200);
DISPLAY INVISIBLE (-6225 2200);
FORCEPROP 1 LAST COMMENT_BODY TRUE
J 0
(-6425 2225);
DISPLAY 0.872340 (-6425 2225);
PAINT GREEN (-6425 2225);
DISPLAY INVISIBLE (-6425 2225);
FORCEPROP 2 LAST PATH I312
J 0
(-6825 2375);
DISPLAY 1.021277 (-6825 2375);
DISPLAY INVISIBLE (-6825 2375);
FORCEADD OFFPAGE..5
(-6550 2225);
FORCEPROP 2 LAST $XR0 93 
J 0
(-6774 2225);
DISPLAY 0.638298 (-6774 2225);
PAINT MONO (-6774 2225);
FORCEPROP 2 LAST CDS_LIB standard
J 0
(-6550 2225);
DISPLAY INVISIBLE (-6550 2225);
FORCEPROP 1 LAST OFFPAGE TRUE
J 0
(-6225 2100);
DISPLAY 0.872340 (-6225 2100);
PAINT GREEN (-6225 2100);
DISPLAY INVISIBLE (-6225 2100);
FORCEPROP 1 LAST COMMENT_BODY TRUE
J 0
(-6450 2150);
DISPLAY 0.872340 (-6450 2150);
PAINT GREEN (-6450 2150);
DISPLAY INVISIBLE (-6450 2150);
FORCEPROP 2 LAST PATH I313
J 0
(-6800 2275);
DISPLAY 1.021277 (-6800 2275);
DISPLAY INVISIBLE (-6800 2275);
FORCEADD Q_RES..1
(-6875 2125);
FORCEPROP 1 LAST LOCATION R382
J 0
(-7200 2125);
DISPLAY 0.489362 (-7200 2125);
PAINT SKYBLUE (-7200 2125);
FORCEPROP 0 LAST $SEC 1
J 0
(-7050 2175);
DISPLAY 0.680851 (-7050 2175);
PAINT MONO (-7050 2175);
DISPLAY INVISIBLE (-7050 2175);
FORCEPROP 0 LAST CDS_SEC 1
J 0
(-7050 2175);
DISPLAY 1.021277 (-7050 2175);
DISPLAY INVISIBLE (-7050 2175);
FORCEPROP 1 LASTPIN (-6975 2125) $PN 1
J 0
(-6963 2137);
DISPLAY 0.489362 (-6963 2137);
PAINT MONO (-6963 2137);
FORCEPROP 1 LASTPIN (-6775 2125) $PN 2
J 0
(-6813 2137);
DISPLAY 0.489362 (-6813 2137);
PAINT MONO (-6813 2137);
FORCEPROP 1 LAST PACK_TYPE 0402LF
J 0
(-7200 2100);
DISPLAY 0.489362 (-7200 2100);
PAINT SKYBLUE (-7200 2100);
FORCEPROP 1 LAST TOLERANCE 1%
J 0
(-6600 2125);
DISPLAY 0.489362 (-6600 2125);
PAINT SKYBLUE (-6600 2125);
FORCEPROP 1 LAST VALUE 15
J 2
(-6550 2125);
DISPLAY 0.489362 (-6550 2125);
PAINT SKYBLUE (-6550 2125);
FORCEPROP 1 LAST MATERIAL CHIP
J 0
(-7000 2250);
DISPLAY 0.638298 (-7000 2250);
PAINT SKYBLUE (-7000 2250);
DISPLAY INVISIBLE (-7000 2250);
FORCEPROP 1 LAST WATTAGE 1/16W
J 2
(-6650 2250);
DISPLAY 0.638298 (-6650 2250);
PAINT SKYBLUE (-6650 2250);
DISPLAY INVISIBLE (-6650 2250);
FORCEPROP 2 LAST CDS_LIB pure_quanta
J 0
(-6875 2125);
DISPLAY INVISIBLE (-6875 2125);
FORCEPROP 1 LAST PATH I314
J 0
(-6925 2275);
DISPLAY 0.978723 (-6925 2275);
PAINT WHITE (-6925 2275);
DISPLAY INVISIBLE (-6925 2275);
FORCEPROP 1 LAST PART_NUMBER CS01502FB03
J 0
(-6775 2100);
DISPLAY 0.489362 (-6775 2100);
PAINT SKYBLUE (-6775 2100);
DISPLAY INVISIBLE (-6775 2100);
FORCEADD OFFPAGE..1
(-7750 2125);
FORCEPROP 2 LAST $XR0 93 
J 0
(-7971 2125);
DISPLAY 0.638298 (-7971 2125);
PAINT MONO (-7971 2125);
FORCEPROP 2 LAST CDS_LIB mstr_standard
J 0
(-7750 2125);
DISPLAY INVISIBLE (-7750 2125);
FORCEPROP 1 LAST OFFPAGE TRUE
J 0
(-7425 2000);
DISPLAY 0.872340 (-7425 2000);
PAINT GREEN (-7425 2000);
DISPLAY INVISIBLE (-7425 2000);
FORCEPROP 1 LAST COMMENT_BODY TRUE
J 0
(-7625 2025);
DISPLAY 0.872340 (-7625 2025);
PAINT GREEN (-7625 2025);
DISPLAY INVISIBLE (-7625 2025);
FORCEPROP 2 LAST PATH I315
J 0
(-8000 2175);
DISPLAY 1.021277 (-8000 2175);
DISPLAY INVISIBLE (-8000 2175);
FORCEADD OFFPAGE..5
(-6550 2025);
FORCEPROP 2 LAST $XR0 93 
J 0
(-6774 2025);
DISPLAY 0.638298 (-6774 2025);
PAINT MONO (-6774 2025);
FORCEPROP 2 LAST CDS_LIB standard
J 0
(-6550 2025);
DISPLAY INVISIBLE (-6550 2025);
FORCEPROP 1 LAST OFFPAGE TRUE
J 0
(-6225 1900);
DISPLAY 0.872340 (-6225 1900);
PAINT GREEN (-6225 1900);
DISPLAY INVISIBLE (-6225 1900);
FORCEPROP 1 LAST COMMENT_BODY TRUE
J 0
(-6450 1950);
DISPLAY 0.872340 (-6450 1950);
PAINT GREEN (-6450 1950);
DISPLAY INVISIBLE (-6450 1950);
FORCEPROP 2 LAST PATH I316
J 0
(-6800 2075);
DISPLAY 1.021277 (-6800 2075);
DISPLAY INVISIBLE (-6800 2075);
FORCEADD QUANTA_TITLE_BLOCK_C..1
(0 0);
FORCEPROP 0 LAST CDS_CON_LAST_MODIFIED Thu Sep 14 16:11:50 2023
J 0
(-1885 15);
DISPLAY INVISIBLE (-1885 15);
FORCEPROP 1 LAST CUSTOM_TXT_CDS <CON_LAST_MODIFIED>
J 0
(-1885 15);
DISPLAY 0.978723 (-1885 15);
FORCEPROP 2 LAST CUSTOM_TXT_CDS <XR_PAGE_TITLE>
J 0
(-7890 5250);
DISPLAY 0.638298 (-7890 5250);
PAINT PINK (-7890 5250);
DISPLAY INVISIBLE (-7890 5250);
FORCEPROP 1 LAST CUSTOM_TXT_CDS <NAME_2>
J 0
(-3175 50);
FORCEPROP 1 LAST CUSTOM_TXT_CDS <NAME_1>
J 0
(-3175 175);
FORCEPROP 1 LAST CUSTOM_TXT_CDS <Q_NUMBER>
J 0
(-1403 103);
DISPLAY 1.212766 (-1403 103);
FORCEPROP 1 LAST CUSTOM_TXT_CDS <Q_PROJ>
J 0
(-2382 102);
DISPLAY 1.212766 (-2382 102);
FORCEPROP 1 LAST CUSTOM_TXT_CDS <Q_REV>
J 0
(-184 103);
DISPLAY 1.212766 (-184 103);
FORCEPROP 1 LAST CUSTOM_TXT_CDS <CON_PAGE_NUM> OF <CON_TOTAL_PAGES>
J 0
(-446 18);
DISPLAY 0.978723 (-446 18);
FORCEPROP 1 LAST Q_TITLE CPU0 DDR CHH
J 0
(-9275 50);
DISPLAY 2.446809 (-9275 50);
PAINT GREEN (-9275 50);
FORCEPROP 2 LAST CDS_LIB pure_quanta
J 0
(0 0);
DISPLAY INVISIBLE (0 0);
FORCEPROP 1 LAST CDS_LMAN_SYM_OUTLINE -9475,6775,100,-125
J 0
(0 0);
DISPLAY 0.468085 (0 0);
PAINT GREEN (0 0);
DISPLAY INVISIBLE (0 0);
FORCEPROP 2 LAST PAGE_BORDER TRUE
J 0
(-7890 5250);
DISPLAY 0.638298 (-7890 5250);
PAINT PINK (-7890 5250);
DISPLAY INVISIBLE (-7890 5250);
FORCEPROP 2 LAST CDS_XR_PAGE_TITLE CR-17 : @T6G_MB_LIB.T6G(SCH_1):PAGE17
J 0
(-7890 5250);
DISPLAY 0.638298 (-7890 5250);
PAINT PINK (-7890 5250);
DISPLAY INVISIBLE (-7890 5250);
FORCEPROP 1 LAST Q_DEPT BU9
J 1
(-3763 49);
DISPLAY 1.957447 (-3763 49);
PAINT GREEN (-3763 49);
DISPLAY INVISIBLE (-3763 49);
FORCEPROP 1 LAST COMMENT_BODY TRUE
J 0
(12 -13);
DISPLAY 0.978723 (12 -13);
PAINT GREEN (12 -13);
DISPLAY INVISIBLE (12 -13);
FORCEADD CAD_NOTE..1
(-7700 2425);
FORCEPROP 0 LAST L1 R1947 PLACE CLOSE TO CPU < 25MM
J 0
(-7850 2300);
DISPLAY 0.617021 (-7850 2300);
PAINT WHITE (-7850 2300);
FORCEPROP 2 LAST CDS_LIB pure_quanta_power
J 0
(-7700 2425);
DISPLAY INVISIBLE (-7700 2425);
FORCEPROP 1 LAST COMMENT_BODY TRUE
J 0
(-7675 2525);
DISPLAY 0.574468 (-7675 2525);
PAINT WHITE (-7675 2525);
DISPLAY INVISIBLE (-7675 2525);
WIRE 17 -1 (-3275 5250)(-3275 5200);
WIRE 17 -1 (-3275 5300)(-3275 5250);
WIRE 17 -1 (-3275 5100)(-3275 5200);
WIRE 17 -1 (-3275 5050)(-3275 5100);
WIRE 17 -1 (-3275 5350)(-3275 5300);
WIRE 17 -1 (-3275 5400)(-3275 5350);
WIRE 17 -1 (-3275 5000)(-3275 5050);
WIRE 17 -1 (-3275 4950)(-3275 5000);
WIRE 17 -1 (-3275 5450)(-3275 5400);
WIRE 17 -1 (-3275 5500)(-3275 5450);
WIRE 17 -1 (-3275 4950)(-3275 4900);
WIRE 17 -1 (-3275 4900)(-3275 4850);
WIRE 17 -1 (-3275 5550)(-3275 5500);
WIRE 17 -1 (-3275 5650)(-3275 5550);
WIRE 17 -1 (-3275 4850)(-3275 4800);
WIRE 17 -1 (-3275 4800)(-3275 4750);
WIRE 17 -1 (-3275 5700)(-3275 5650);
WIRE 17 -1 (-3275 5750)(-3275 5700);
WIRE 17 -1 (-3275 4750)(-3275 4650);
WIRE 17 -1 (-3275 4650)(-3275 4600);
WIRE 17 -1 (-3275 5800)(-3275 5750);
WIRE 17 -1 (-3275 5850)(-3275 5800);
WIRE 17 -1 (-3275 4600)(-3275 4550);
WIRE 17 -1 (-3275 4550)(-3275 4500);
WIRE 17 -1 (-3275 5900)(-3275 5850);
WIRE 17 -1 (-3275 5950)(-3275 5900);
WIRE 17 -1 (-3275 4450)(-3275 4500);
WIRE 17 -1 (-3275 4400)(-3275 4450);
WIRE 17 -1 (-3275 6000)(-3275 5950);
WIRE 17 -1 (-3275 6000)(-2650 6000);
FORCEPROP 2 LAST SIG_NAME M_H_CPU0_SA_DQ<31:0>
J 2
(-2710 6010);
DISPLAY 0.489362 (-2710 6010);
WIRE 17 -1 (-3275 4350)(-3275 4400);
WIRE 17 -1 (-3275 4300)(-3275 4350);
WIRE 17 -1 (-3275 4200)(-2650 4200);
FORCEPROP 2 LAST SIG_NAME M_H_CPU0_SB_DQ<31:0>
J 2
(-2710 4210);
DISPLAY 0.489362 (-2710 4210);
WIRE 17 -1 (-3275 4200)(-3275 4150);
WIRE 17 -1 (-3275 3150)(-3275 3100);
WIRE 17 -1 (-3275 3150)(-3275 3200);
WIRE 17 -1 (-3275 3100)(-3275 3050);
WIRE 17 -1 (-3275 3050)(-3275 3000);
WIRE 17 -1 (-3275 3200)(-3275 3250);
WIRE 17 -1 (-3275 3250)(-3275 3300);
WIRE 17 -1 (-3275 3000)(-3275 2950);
WIRE 17 -1 (-3275 2950)(-3275 2850);
WIRE 17 -1 (-3275 3300)(-3275 3400);
WIRE 17 -1 (-3275 3450)(-3275 3400);
WIRE 17 -1 (-3275 2850)(-3275 2800);
WIRE 17 -1 (-3275 2800)(-3275 2750);
WIRE 17 -1 (-3275 3500)(-3275 3450);
WIRE 17 -1 (-3275 3550)(-3275 3500);
WIRE 17 -1 (-3275 2750)(-3275 2700);
WIRE 17 -1 (-3275 2650)(-3275 2700);
WIRE 17 -1 (-3275 3600)(-3275 3550);
WIRE 17 -1 (-3275 3650)(-3275 3600);
WIRE 17 -1 (-3275 2600)(-3275 2650);
WIRE 17 -1 (-3275 2550)(-3275 2600);
WIRE 17 -1 (-3275 3700)(-3275 3650);
WIRE 17 -1 (-3275 3750)(-3275 3700);
WIRE 17 -1 (-3275 2500)(-3275 2550);
WIRE 17 -1 (-3275 3850)(-3275 3750);
WIRE 17 -1 (-3275 3900)(-3275 3850);
WIRE 17 -1 (-3275 3950)(-3275 3900);
WIRE 17 -1 (-3275 4000)(-3275 3950);
WIRE 17 -1 (-3275 4050)(-3275 4000);
WIRE 17 -1 (-3275 4100)(-3275 4050);
WIRE 17 -1 (-3275 4150)(-3275 4100);
WIRE 17 -1 (-3275 2100)(-3275 2150);
WIRE 17 -1 (-3275 2050)(-3275 2100);
WIRE 17 -1 (-3275 2150)(-3275 2200);
WIRE 17 -1 (-3275 2200)(-3275 2250);
WIRE 17 -1 (-3275 2300)(-3275 2250);
WIRE 17 -1 (-3275 2300)(-3275 2350);
WIRE 17 -1 (-3275 2400)(-3275 2350);
WIRE 17 -1 (-3275 2400)(-3275 2425);
WIRE 17 -1 (-3275 2425)(-2775 2425);
FORCEPROP 2 LAST SIG_NAME M_H_CPU0_SA_CB<7:0>
J 2
(-2775 2435);
DISPLAY 0.489362 (-2775 2435);
WIRE 17 -1 (-3275 1950)(-3275 1975);
WIRE 17 -1 (-3275 1950)(-3275 1900);
WIRE 17 -1 (-3275 1975)(-2775 1975);
FORCEPROP 2 LAST SIG_NAME M_H_CPU0_SB_CB<7:0>
J 2
(-2775 1985);
DISPLAY 0.489362 (-2775 1985);
WIRE 17 -1 (-3275 1850)(-3275 1900);
WIRE 17 -1 (-3275 1850)(-3275 1800);
WIRE 17 -1 (-3275 1750)(-3275 1800);
WIRE 17 -1 (-3275 1700)(-3275 1750);
WIRE 17 -1 (-3275 1650)(-3275 1700);
WIRE 17 -1 (-3275 1600)(-3275 1650);
WIRE 17 -1 (-6000 5850)(-6000 5750);
WIRE 17 -1 (-6000 5950)(-6000 5850);
FORCEPROP 2 LAST SIG_NAME M_H_CPU0_SA_DQS_DN<9:0>
J 2
(-6035 5960);
DISPLAY 0.489362 (-6035 5960);
WIRE 17 -1 (-6000 5750)(-6000 5650);
WIRE 17 -1 (-6000 5650)(-6000 5550);
WIRE 17 -1 (-6000 5450)(-6000 5550);
WIRE 17 -1 (-6000 5350)(-6000 5450);
WIRE 17 -1 (-5800 6000)(-5800 5900);
WIRE 17 -1 (-5800 6000)(-6600 6000);
FORCEPROP 2 LAST SIG_NAME M_H_CPU0_SA_DQS_DP<9:0>
J 2
(-6035 6010);
DISPLAY 0.489362 (-6035 6010);
WIRE 17 -1 (-6000 5250)(-6000 5350);
WIRE 17 -1 (-6000 5250)(-6000 5150);
WIRE 17 -1 (-6000 5150)(-6000 5050);
WIRE 17 -1 (-5800 5900)(-5800 5800);
WIRE 17 -1 (-5800 5800)(-5800 5700);
WIRE 17 -1 (-5800 5700)(-5800 5600);
WIRE 17 -1 (-5800 5500)(-5800 5600);
WIRE 17 -1 (-5800 5400)(-5800 5500);
WIRE 17 -1 (-5800 5300)(-5800 5400);
WIRE 17 -1 (-5800 5300)(-5800 5200);
WIRE 17 -1 (-5800 5200)(-5800 5100);
WIRE 17 -1 (-6000 4900)(-6000 4800);
FORCEPROP 2 LAST SIG_NAME M_H_CPU0_SB_DQS_DN<9:0>
J 2
(-6035 4910);
DISPLAY 0.489362 (-6035 4910);
WIRE 17 -1 (-6000 4800)(-6000 4700);
WIRE 17 -1 (-6000 4700)(-6000 4600);
WIRE 17 -1 (-6000 4600)(-6000 4500);
WIRE 17 -1 (-6000 4400)(-6000 4500);
WIRE 17 -1 (-6000 4300)(-6000 4400);
WIRE 17 -1 (-5800 4950)(-5800 4850);
WIRE 17 -1 (-5800 4950)(-6600 4950);
FORCEPROP 2 LAST SIG_NAME M_H_CPU0_SB_DQS_DP<9:0>
J 2
(-6035 4960);
DISPLAY 0.489362 (-6035 4960);
WIRE 17 -1 (-6000 4200)(-6000 4300);
WIRE 17 -1 (-6000 4200)(-6000 4100);
WIRE 17 -1 (-6000 4100)(-6000 4000);
WIRE 17 -1 (-5800 4850)(-5800 4750);
WIRE 17 -1 (-5800 4750)(-5800 4650);
WIRE 17 -1 (-5800 4650)(-5800 4550);
WIRE 17 -1 (-5800 4450)(-5800 4550);
WIRE 17 -1 (-5800 4350)(-5800 4450);
WIRE 17 -1 (-5800 4250)(-5800 4350);
WIRE 17 -1 (-5800 4250)(-5800 4150);
WIRE 17 -1 (-5800 4150)(-5800 4050);
WIRE 17 -1 (-6000 3800)(-6000 3850);
WIRE 17 -1 (-6000 3750)(-6000 3800);
WIRE 17 -1 (-6000 3850)(-6500 3850);
FORCEPROP 2 LAST SIG_NAME M_H_CPU0_SA_CA<6:0>
J 0
(-6500 3860);
DISPLAY 0.489362 (-6500 3860);
WIRE 17 -1 (-6000 3400)(-6000 3450);
WIRE 17 -1 (-6000 3350)(-6000 3400);
WIRE 17 -1 (-6000 3450)(-6500 3450);
FORCEPROP 2 LAST SIG_NAME M_H_CPU0_SB_CA<6:0>
J 0
(-6500 3460);
DISPLAY 0.489362 (-6500 3460);
WIRE 17 -1 (-6000 3700)(-6000 3750);
WIRE 17 -1 (-6000 3300)(-6000 3350);
WIRE 17 -1 (-6000 3650)(-6000 3700);
WIRE 17 -1 (-6000 3600)(-6000 3650);
WIRE 17 -1 (-6000 3550)(-6000 3600);
WIRE 17 -1 (-6000 3250)(-6000 3300);
WIRE 17 -1 (-6000 3200)(-6000 3250);
WIRE 17 -1 (-6000 3150)(-6000 3200);
WIRE 17 -1 (-6000 5950)(-6600 5950);
WIRE 17 -1 (-6000 4900)(-6600 4900);
WIRE 16 -1 (-7700 2125)(-6975 2125);
FORCEPROP 2 LAST SIG_NAME M_H_CPU0_ALERT_N
J 0
(-7660 2135);
DISPLAY 0.489362 (-7660 2135);
WIRE 16 -1 (-6775 2125)(-5400 2125);
FORCEPROP 2 LAST SIG_NAME M_H_CPU0_ALERT_R_N
J 0
(-6485 2135);
DISPLAY 0.489362 (-6485 2135);
FORCEPROP 2 LASTPROP $XRERR UNIQUE?
J 0
(-6725 2135);
DISPLAY 0.638298 (-6725 2135);
PAINT MONO (-6725 2135);
DISPLAY INVISIBLE (-6725 2135);
WIRE 16 -1 (-6500 1175)(-5400 1175);
FORCEPROP 2 LAST SIG_NAME TP_M_H_CPU0_SA_TEST39H
J 0
(-6485 1185);
DISPLAY 0.489362 (-6485 1185);
FORCEPROP 2 LASTPROP $XRERR UNIQUE?
J 0
(-6740 1175);
DISPLAY 0.638298 (-6740 1175);
PAINT MONO (-6740 1175);
DISPLAY INVISIBLE (-6740 1175);
WIRE 16 -1 (-6500 2975)(-5400 2975);
FORCEPROP 2 LAST SIG_NAME M_H_CPU0_CLK_DP<0>
J 0
(-6500 2985);
DISPLAY 0.489362 (-6500 2985);
WIRE 16 -1 (-6500 2925)(-5400 2925);
FORCEPROP 2 LAST SIG_NAME M_H_CPU0_CLK_DN<0>
J 0
(-6500 2935);
DISPLAY 0.489362 (-6500 2935);
WIRE 16 -1 (-6500 2825)(-5400 2825);
FORCEPROP 2 LAST SIG_NAME M_H_CPU0_SA_CS_N<0>
J 0
(-6500 2835);
DISPLAY 0.489362 (-6500 2835);
WIRE 16 -1 (-6500 2775)(-5400 2775);
FORCEPROP 2 LAST SIG_NAME M_H_CPU0_SA_CS_N<1>
J 0
(-6500 2785);
DISPLAY 0.489362 (-6500 2785);
WIRE 16 -1 (-6500 2675)(-5400 2675);
FORCEPROP 2 LAST SIG_NAME M_H_CPU0_SA_RSP<0>
J 0
(-6500 2685);
DISPLAY 0.489362 (-6500 2685);
WIRE 16 -1 (-6500 2575)(-5400 2575);
FORCEPROP 2 LAST SIG_NAME M_H_CPU0_SA_PAR
J 0
(-6500 2585);
DISPLAY 0.489362 (-6500 2585);
WIRE 16 -1 (-6500 2425)(-5400 2425);
FORCEPROP 2 LAST SIG_NAME M_H_CPU0_SB_CS_N<1>
J 0
(-6500 2435);
DISPLAY 0.489362 (-6500 2435);
WIRE 16 -1 (-6500 2475)(-5400 2475);
FORCEPROP 2 LAST SIG_NAME M_H_CPU0_SB_CS_N<0>
J 0
(-6500 2485);
DISPLAY 0.489362 (-6500 2485);
WIRE 16 -1 (-6500 2325)(-5400 2325);
FORCEPROP 2 LAST SIG_NAME M_H_CPU0_SB_RSP<0>
J 0
(-6500 2335);
DISPLAY 0.489362 (-6500 2335);
WIRE 16 -1 (-6500 2225)(-5400 2225);
FORCEPROP 2 LAST SIG_NAME M_H_CPU0_SB_PAR
J 0
(-6500 2235);
DISPLAY 0.489362 (-6500 2235);
WIRE 16 -1 (-6500 2025)(-5400 2025);
FORCEPROP 2 LAST SIG_NAME M_H_CPU0_RESET_N
J 0
(-6500 2035);
DISPLAY 0.489362 (-6500 2035);
WIRE 16 -1 (-5700 4025)(-5400 4025);
WIRE 16 -1 (-5900 3975)(-5400 3975);
WIRE 16 -1 (-5900 4075)(-5400 4075);
WIRE 16 -1 (-5900 3125)(-5400 3125);
WIRE 16 -1 (-5900 3525)(-5400 3525);
WIRE 16 -1 (-5900 3175)(-5400 3175);
WIRE 16 -1 (-5900 3575)(-5400 3575);
WIRE 16 -1 (-5900 3225)(-5400 3225);
WIRE 16 -1 (-5900 3625)(-5400 3625);
WIRE 16 -1 (-5900 3275)(-5400 3275);
WIRE 16 -1 (-5900 3675)(-5400 3675);
WIRE 16 -1 (-5900 3325)(-5400 3325);
WIRE 16 -1 (-5900 3725)(-5400 3725);
WIRE 16 -1 (-5900 3375)(-5400 3375);
WIRE 16 -1 (-5900 3775)(-5400 3775);
WIRE 16 -1 (-5900 3425)(-5400 3425);
WIRE 16 -1 (-5900 3825)(-5400 3825);
WIRE 16 -1 (-5700 4125)(-5400 4125);
WIRE 16 -1 (-5700 4225)(-5400 4225);
WIRE 16 -1 (-5700 4325)(-5400 4325);
WIRE 16 -1 (-5700 4425)(-5400 4425);
WIRE 16 -1 (-5700 4525)(-5400 4525);
WIRE 16 -1 (-5700 5075)(-5400 5075);
WIRE 16 -1 (-5700 4625)(-5400 4625);
WIRE 16 -1 (-5900 4175)(-5400 4175);
WIRE 16 -1 (-5700 4725)(-5400 4725);
WIRE 16 -1 (-5900 4275)(-5400 4275);
WIRE 16 -1 (-5700 4825)(-5400 4825);
WIRE 16 -1 (-5900 4375)(-5400 4375);
WIRE 16 -1 (-5700 4925)(-5400 4925);
WIRE 16 -1 (-5900 4475)(-5400 4475);
WIRE 16 -1 (-5900 5025)(-5400 5025);
WIRE 16 -1 (-5900 4575)(-5400 4575);
WIRE 16 -1 (-5900 4675)(-5400 4675);
WIRE 16 -1 (-5900 4775)(-5400 4775);
WIRE 16 -1 (-5900 4875)(-5400 4875);
WIRE 16 -1 (-5900 5825)(-5400 5825);
WIRE 16 -1 (-5900 5925)(-5400 5925);
WIRE 16 -1 (-5700 5175)(-5400 5175);
WIRE 16 -1 (-5700 5275)(-5400 5275);
WIRE 16 -1 (-5700 5375)(-5400 5375);
WIRE 16 -1 (-5700 5475)(-5400 5475);
WIRE 16 -1 (-5700 5575)(-5400 5575);
WIRE 16 -1 (-5900 5125)(-5400 5125);
WIRE 16 -1 (-5700 5675)(-5400 5675);
WIRE 16 -1 (-5900 5225)(-5400 5225);
WIRE 16 -1 (-5700 5775)(-5400 5775);
WIRE 16 -1 (-5900 5325)(-5400 5325);
WIRE 16 -1 (-5700 5875)(-5400 5875);
WIRE 16 -1 (-5900 5425)(-5400 5425);
WIRE 16 -1 (-5700 5975)(-5400 5975);
WIRE 16 -1 (-5900 5525)(-5400 5525);
WIRE 16 -1 (-5900 5625)(-5400 5625);
WIRE 16 -1 (-5900 5725)(-5400 5725);
WIRE 16 -1 (-3800 1575)(-3375 1575);
WIRE 16 -1 (-3800 1625)(-3375 1625);
WIRE 16 -1 (-3800 1675)(-3375 1675);
WIRE 16 -1 (-3800 1725)(-3375 1725);
WIRE 16 -1 (-3800 1775)(-3375 1775);
WIRE 16 -1 (-3800 1825)(-3375 1825);
WIRE 16 -1 (-3800 2025)(-3375 2025);
WIRE 16 -1 (-3800 1875)(-3375 1875);
WIRE 16 -1 (-3800 1925)(-3375 1925);
WIRE 16 -1 (-3800 2125)(-3375 2125);
WIRE 16 -1 (-3800 2525)(-3375 2525);
WIRE 16 -1 (-3800 2175)(-3375 2175);
WIRE 16 -1 (-3800 2225)(-3375 2225);
WIRE 16 -1 (-3800 2275)(-3375 2275);
WIRE 16 -1 (-3800 2325)(-3375 2325);
WIRE 16 -1 (-3800 2375)(-3375 2375);
WIRE 16 -1 (-3800 2575)(-3375 2575);
WIRE 16 -1 (-3800 2625)(-3375 2625);
WIRE 16 -1 (-3800 2675)(-3375 2675);
WIRE 16 -1 (-3800 2725)(-3375 2725);
WIRE 16 -1 (-3800 2775)(-3375 2775);
WIRE 16 -1 (-3800 2825)(-3375 2825);
WIRE 16 -1 (-3800 2925)(-3375 2925);
WIRE 16 -1 (-3800 2975)(-3375 2975);
WIRE 16 -1 (-3800 3025)(-3375 3025);
WIRE 16 -1 (-3800 2075)(-3375 2075);
WIRE 16 -1 (-3800 2475)(-3375 2475);
WIRE 16 -1 (-3800 3675)(-3375 3675);
WIRE 16 -1 (-3800 3725)(-3375 3725);
WIRE 16 -1 (-3800 3825)(-3375 3825);
WIRE 16 -1 (-3800 3875)(-3375 3875);
WIRE 16 -1 (-3800 3925)(-3375 3925);
WIRE 16 -1 (-3800 3125)(-3375 3125);
WIRE 16 -1 (-3800 3975)(-3375 3975);
WIRE 16 -1 (-3800 3175)(-3375 3175);
WIRE 16 -1 (-3800 4025)(-3375 4025);
WIRE 16 -1 (-3800 3225)(-3375 3225);
WIRE 16 -1 (-3800 4075)(-3375 4075);
WIRE 16 -1 (-3800 3275)(-3375 3275);
WIRE 16 -1 (-3800 3375)(-3375 3375);
WIRE 16 -1 (-3800 3425)(-3375 3425);
WIRE 16 -1 (-3800 3475)(-3375 3475);
WIRE 16 -1 (-3800 3525)(-3375 3525);
WIRE 16 -1 (-3800 3575)(-3375 3575);
WIRE 16 -1 (-3800 3625)(-3375 3625);
WIRE 16 -1 (-3800 3075)(-3375 3075);
WIRE 16 -1 (-3800 4575)(-3375 4575);
WIRE 16 -1 (-3800 4625)(-3375 4625);
WIRE 16 -1 (-3800 4725)(-3375 4725);
WIRE 16 -1 (-3800 4775)(-3375 4775);
WIRE 16 -1 (-3800 4825)(-3375 4825);
WIRE 16 -1 (-3800 4875)(-3375 4875);
WIRE 16 -1 (-3800 4275)(-3375 4275);
WIRE 16 -1 (-3800 4325)(-3375 4325);
WIRE 16 -1 (-3800 4125)(-3375 4125);
WIRE 16 -1 (-3800 4175)(-3375 4175);
WIRE 16 -1 (-3800 4925)(-3375 4925);
WIRE 16 -1 (-3800 4975)(-3375 4975);
WIRE 16 -1 (-3800 4375)(-3375 4375);
WIRE 16 -1 (-3800 5025)(-3375 5025);
WIRE 16 -1 (-3800 4425)(-3375 4425);
WIRE 16 -1 (-3800 5075)(-3375 5075);
WIRE 16 -1 (-3800 4475)(-3375 4475);
WIRE 16 -1 (-3800 4525)(-3375 4525);
WIRE 16 -1 (-3800 5225)(-3375 5225);
WIRE 16 -1 (-3800 5275)(-3375 5275);
WIRE 16 -1 (-3800 5475)(-3375 5475);
WIRE 16 -1 (-3800 5325)(-3375 5325);
WIRE 16 -1 (-3800 5525)(-3375 5525);
WIRE 16 -1 (-3800 5375)(-3375 5375);
WIRE 16 -1 (-3800 5625)(-3375 5625);
WIRE 16 -1 (-3800 5425)(-3375 5425);
WIRE 16 -1 (-3800 5675)(-3375 5675);
WIRE 16 -1 (-3800 5725)(-3375 5725);
WIRE 16 -1 (-3800 5775)(-3375 5775);
WIRE 16 -1 (-3800 5825)(-3375 5825);
WIRE 16 -1 (-3800 5875)(-3375 5875);
WIRE 16 -1 (-3800 5925)(-3375 5925);
WIRE 16 -1 (-3800 5975)(-3375 5975);
WIRE 16 -1 (-3800 5175)(-3375 5175);
QUIT
